FILE_TYPE = MACRO_DRAWING;
SET COLOR_WIRE YELLOW;
SET COLOR_PROP MONO;
SET COLOR_DOT WHITE;
SET COLOR_ARC YELLOW;
SET COLOR_BODY GREEN;
SET COLOR_NOTE MONO;
SET PROP_DISPLAY VALUE;
SET PAGE_NUMBER P152;
FORCEADD GTL2014..1
R 2
(-5400 4050);
FORCEPROP 2 LASTPIN (-5850 4050) $PN 6
J 2
(-5860 4060);
DISPLAY 0.617021 (-5860 4060);
PAINT ORANGE (-5860 4060);
FORCEPROP 2 LASTPIN (-5850 3900) $PN 2
J 2
(-5860 3910);
DISPLAY 0.617021 (-5860 3910);
PAINT ORANGE (-5860 3910);
FORCEPROP 2 LASTPIN (-5850 3950) $PN 3
J 2
(-5860 3960);
DISPLAY 0.617021 (-5860 3960);
PAINT ORANGE (-5860 3960);
FORCEPROP 2 LASTPIN (-5850 4000) $PN 5
J 2
(-5860 4010);
DISPLAY 0.617021 (-5860 4010);
PAINT ORANGE (-5860 4010);
FORCEPROP 2 LASTPIN (-5850 3650) $PN 7
J 2
(-5860 3660);
DISPLAY 0.617021 (-5860 3660);
PAINT ORANGE (-5860 3660);
FORCEPROP 2 LASTPIN (-5850 3700) $PN 8
J 2
(-5860 3710);
DISPLAY 0.617021 (-5860 3710);
PAINT ORANGE (-5860 3710);
FORCEPROP 2 LASTPIN (-5850 3750) $PN 11
J 2
(-5860 3760);
DISPLAY 0.617021 (-5860 3760);
PAINT ORANGE (-5860 3760);
FORCEPROP 1 LAST PART_NUMBER D66151-001
J 2
(-5000 3550);
DISPLAY 0.617021 (-5000 3550);
PAINT BLUE (-5000 3550);
FORCEPROP 2 LASTPIN (-4950 3900) $PN 13
J 0
(-4940 3910);
DISPLAY 0.617021 (-4940 3910);
PAINT ORANGE (-4940 3910);
FORCEPROP 2 LASTPIN (-4950 3950) $PN 12
J 0
(-4940 3960);
DISPLAY 0.617021 (-4940 3960);
PAINT ORANGE (-4940 3960);
FORCEPROP 2 LASTPIN (-4950 4000) $PN 10
J 0
(-4940 4010);
DISPLAY 0.617021 (-4940 4010);
PAINT ORANGE (-4940 4010);
FORCEPROP 2 LASTPIN (-4950 4050) $PN 9
J 0
(-4940 4060);
DISPLAY 0.617021 (-4940 4060);
PAINT ORANGE (-4940 4060);
FORCEPROP 1 LAST MATERIAL IC
J 2
(-5000 4550);
DISPLAY 0.617021 (-5000 4550);
PAINT SKYBLUE (-5000 4550);
FORCEPROP 2 LASTPIN (-4950 4300) $PN 4
J 0
(-4940 4310);
DISPLAY 0.617021 (-4940 4310);
PAINT ORANGE (-4940 4310);
FORCEPROP 2 LASTPIN (-4950 4350) $PN 14
J 0
(-4940 4360);
DISPLAY 0.617021 (-4940 4360);
PAINT ORANGE (-4940 4360);
FORCEPROP 2 LASTPIN (-4950 4200) $PN 1
J 0
(-4940 4210);
DISPLAY 0.617021 (-4940 4210);
PAINT ORANGE (-4940 4210);
FORCEPROP 1 LAST LOCATION U9G1
J 2
(-5000 4600);
DISPLAY 0.617021 (-5000 4600);
PAINT AQUA (-5000 4600);
FORCEPROP 2 LAST CDS_LIB mstr_digital
J 2
(-5400 4050);
PAINT ORANGE (-5400 4050);
DISPLAY INVISIBLE (-5400 4050);
FORCEPROP 1 LAST PATH I1
J 2
(-5400 4550);
PAINT GREEN (-5400 4550);
DISPLAY INVISIBLE (-5400 4550);
FORCEPROP 2 LAST CDS_LOCATION U9G1
J 2
(-5000 4600);
DISPLAY 0.617021 (-5000 4600);
PAINT AQUA (-5000 4600);
DISPLAY INVISIBLE (-5000 4600);
FORCEPROP 2 LAST ROOM PROC_SIDEBAND
J 0
(-5000 4650);
DISPLAY 1.021277 (-5000 4650);
PAINT ORANGE (-5000 4650);
DISPLAY INVISIBLE (-5000 4650);
FORCEPROP 1 LAST PACK_TYPE SM
J 2
(-5000 4650);
PAINT SKYBLUE (-5000 4650);
DISPLAY INVISIBLE (-5000 4650);
FORCEPROP 2 LAST SEC_TYPE SM
J 0
(-5000 4650);
DISPLAY 1.021277 (-5000 4650);
PAINT ORANGE (-5000 4650);
DISPLAY INVISIBLE (-5000 4650);
FORCEPROP 2 LAST BOM_COST PROC_SIDEBAND
J 0
(-5000 4700);
DISPLAY 1.021277 (-5000 4700);
PAINT ORANGE (-5000 4700);
DISPLAY INVISIBLE (-5000 4700);
FORCEPROP 2 LAST SEC 1
J 0
(-5000 4650);
DISPLAY 0.680851 (-5000 4650);
PAINT MONO (-5000 4650);
DISPLAY INVISIBLE (-5000 4650);
FORCEADD OFFPAGE..2
(-1575 4250);
FORCEPROP 2 LAST $XR0 152 
J 0
(-1386 4250);
DISPLAY 0.638298 (-1386 4250);
PAINT MONO (-1386 4250);
FORCEPROP 1 LAST COMMENT_BODY TRUE
J 0
(-1620 4155);
DISPLAY 0.872340 (-1620 4155);
PAINT GREEN (-1620 4155);
DISPLAY INVISIBLE (-1620 4155);
FORCEPROP 2 LAST CDS_LIB mstr_standard
J 0
(-1575 4250);
PAINT ORANGE (-1575 4250);
DISPLAY INVISIBLE (-1575 4250);
FORCEPROP 2 LAST PATH I10
J 0
(-1525 4325);
DISPLAY 1.021277 (-1525 4325);
PAINT ORANGE (-1525 4325);
DISPLAY INVISIBLE (-1525 4325);
FORCEPROP 1 LAST OFFPAGE TRUE
J 0
(-1250 4125);
DISPLAY 0.872340 (-1250 4125);
PAINT GREEN (-1250 4125);
DISPLAY INVISIBLE (-1250 4125);
FORCEADD RES..1
(-6700 1400);
FORCEPROP 1 LAST WATTAGE 1/16W
J 2
(-6800 1350);
DISPLAY 0.617021 (-6800 1350);
PAINT SKYBLUE (-6800 1350);
FORCEPROP 1 LAST VALUE 0.0
J 2
(-6800 1400);
DISPLAY 0.617021 (-6800 1400);
PAINT SKYBLUE (-6800 1400);
FORCEPROP 1 LAST TOLERANCE 5%
J 0
(-6775 1350);
DISPLAY 0.617021 (-6775 1350);
PAINT SKYBLUE (-6775 1350);
FORCEPROP 1 LAST LOCATION R3P63
J 0
(-6750 1450);
DISPLAY 0.617021 (-6750 1450);
PAINT AQUA (-6750 1450);
FORCEPROP 1 LAST PART_NUMBER G21497-005
J 0
(-6850 1500);
DISPLAY 0.617021 (-6850 1500);
PAINT BLUE (-6850 1500);
FORCEPROP 1 LAST MATERIAL EMPTY
J 0
(-6700 1350);
DISPLAY 0.617021 (-6700 1350);
PAINT RED (-6700 1350);
FORCEPROP 1 LAST PACK_TYPE 0402
J 0
(-6550 1350);
DISPLAY 0.617021 (-6550 1350);
PAINT SKYBLUE (-6550 1350);
FORCEPROP 1 LASTPIN (-6800 1400) $PN 1
J 0
(-6788 1412);
DISPLAY 0.787234 (-6788 1412);
PAINT ORANGE (-6788 1412);
DISPLAY INVISIBLE (-6788 1412);
FORCEPROP 2 LAST CDS_LIB mstr_discrete
J 0
(-6700 1400);
PAINT ORANGE (-6700 1400);
DISPLAY INVISIBLE (-6700 1400);
FORCEPROP 1 LAST PATH I100
J 0
(-6750 1550);
DISPLAY 0.978723 (-6750 1550);
PAINT WHITE (-6750 1550);
DISPLAY INVISIBLE (-6750 1550);
FORCEPROP 2 LAST $SEC 1
J 0
(-6750 1600);
PAINT MONO (-6750 1600);
DISPLAY INVISIBLE (-6750 1600);
FORCEPROP 2 LAST CDS_SEC 1
J 0
(-6750 1600);
PAINT MONO (-6750 1600);
DISPLAY INVISIBLE (-6750 1600);
FORCEPROP 1 LASTPIN (-6600 1400) $PN 2
J 0
(-6638 1412);
DISPLAY 0.787234 (-6638 1412);
PAINT ORANGE (-6638 1412);
DISPLAY INVISIBLE (-6638 1412);
FORCEADD OFFPAGE..2
(-5475 975);
FORCEPROP 2 LAST $XR0 121 
J 0
(-5286 975);
DISPLAY 0.638298 (-5286 975);
PAINT MONO (-5286 975);
FORCEPROP 1 LAST COMMENT_BODY TRUE
J 0
(-5520 880);
DISPLAY 0.872340 (-5520 880);
PAINT GREEN (-5520 880);
DISPLAY INVISIBLE (-5520 880);
FORCEPROP 2 LAST CDS_LIB mstr_standard
J 0
(-5475 975);
PAINT ORANGE (-5475 975);
DISPLAY INVISIBLE (-5475 975);
FORCEPROP 1 LAST OFFPAGE TRUE
J 0
(-5150 850);
DISPLAY 0.872340 (-5150 850);
PAINT GREEN (-5150 850);
DISPLAY INVISIBLE (-5150 850);
FORCEPROP 2 LAST PATH I101
J 0
(-5300 1050);
DISPLAY 1.021277 (-5300 1050);
PAINT ORANGE (-5300 1050);
DISPLAY INVISIBLE (-5300 1050);
FORCEADD RES..1
(-6700 975);
FORCEPROP 1 LAST WATTAGE 1/16W
J 2
(-6800 925);
DISPLAY 0.617021 (-6800 925);
PAINT SKYBLUE (-6800 925);
FORCEPROP 1 LAST VALUE 0.0
J 2
(-6800 975);
DISPLAY 0.617021 (-6800 975);
PAINT SKYBLUE (-6800 975);
FORCEPROP 1 LAST TOLERANCE 5%
J 0
(-6775 925);
DISPLAY 0.617021 (-6775 925);
PAINT SKYBLUE (-6775 925);
FORCEPROP 1 LAST MATERIAL EMPTY
J 0
(-6700 925);
DISPLAY 0.617021 (-6700 925);
PAINT RED (-6700 925);
FORCEPROP 1 LAST PACK_TYPE 0402
J 0
(-6550 925);
DISPLAY 0.617021 (-6550 925);
PAINT SKYBLUE (-6550 925);
FORCEPROP 1 LAST PART_NUMBER G21497-005
J 0
(-6850 1075);
DISPLAY 0.617021 (-6850 1075);
PAINT BLUE (-6850 1075);
FORCEPROP 1 LAST LOCATION R2U45
J 0
(-6750 1025);
DISPLAY 0.617021 (-6750 1025);
PAINT AQUA (-6750 1025);
FORCEPROP 1 LASTPIN (-6800 975) $PN 1
J 0
(-6788 987);
DISPLAY 0.787234 (-6788 987);
PAINT ORANGE (-6788 987);
DISPLAY INVISIBLE (-6788 987);
FORCEPROP 2 LAST CDS_LIB mstr_discrete
J 0
(-6700 975);
PAINT ORANGE (-6700 975);
DISPLAY INVISIBLE (-6700 975);
FORCEPROP 1 LASTPIN (-6600 975) $PN 2
J 0
(-6638 987);
DISPLAY 0.787234 (-6638 987);
PAINT ORANGE (-6638 987);
DISPLAY INVISIBLE (-6638 987);
FORCEPROP 1 LAST PATH I102
J 0
(-6750 1125);
DISPLAY 0.978723 (-6750 1125);
PAINT WHITE (-6750 1125);
DISPLAY INVISIBLE (-6750 1125);
FORCEPROP 2 LAST $SEC 1
J 0
(-6750 1175);
PAINT MONO (-6750 1175);
DISPLAY INVISIBLE (-6750 1175);
FORCEPROP 2 LAST CDS_SEC 1
J 0
(-6750 1175);
PAINT MONO (-6750 1175);
DISPLAY INVISIBLE (-6750 1175);
FORCEADD OFFPAGE..2
(-1575 4075);
FORCEPROP 2 LAST $XR0 152 
J 0
(-1386 4075);
DISPLAY 0.638298 (-1386 4075);
PAINT MONO (-1386 4075);
FORCEPROP 1 LAST COMMENT_BODY TRUE
J 0
(-1620 3980);
DISPLAY 0.872340 (-1620 3980);
PAINT GREEN (-1620 3980);
DISPLAY INVISIBLE (-1620 3980);
FORCEPROP 1 LAST OFFPAGE TRUE
J 0
(-1250 3950);
DISPLAY 0.872340 (-1250 3950);
PAINT GREEN (-1250 3950);
DISPLAY INVISIBLE (-1250 3950);
FORCEPROP 2 LAST CDS_LIB mstr_standard
J 0
(-1575 4075);
PAINT ORANGE (-1575 4075);
DISPLAY INVISIBLE (-1575 4075);
FORCEPROP 2 LAST PATH I11
J 0
(-1400 4150);
DISPLAY 1.021277 (-1400 4150);
PAINT ORANGE (-1400 4150);
DISPLAY INVISIBLE (-1400 4150);
FORCEADD OFFPAGE..2
(-1575 3900);
FORCEPROP 2 LAST $XR0 152 
J 0
(-1386 3900);
DISPLAY 0.638298 (-1386 3900);
PAINT MONO (-1386 3900);
FORCEPROP 1 LAST COMMENT_BODY TRUE
J 0
(-1620 3805);
DISPLAY 0.872340 (-1620 3805);
PAINT GREEN (-1620 3805);
DISPLAY INVISIBLE (-1620 3805);
FORCEPROP 2 LAST CDS_LIB mstr_standard
J 0
(-1575 3900);
PAINT ORANGE (-1575 3900);
DISPLAY INVISIBLE (-1575 3900);
FORCEPROP 2 LAST PATH I12
J 0
(-1400 3975);
DISPLAY 1.021277 (-1400 3975);
PAINT ORANGE (-1400 3975);
DISPLAY INVISIBLE (-1400 3975);
FORCEPROP 1 LAST OFFPAGE TRUE
J 0
(-1250 3775);
DISPLAY 0.872340 (-1250 3775);
PAINT GREEN (-1250 3775);
DISPLAY INVISIBLE (-1250 3775);
FORCEADD OFFPAGE..2
(-1575 3725);
FORCEPROP 2 LAST $XR0 152 
J 0
(-1386 3725);
DISPLAY 0.638298 (-1386 3725);
PAINT MONO (-1386 3725);
FORCEPROP 1 LAST COMMENT_BODY TRUE
J 0
(-1620 3630);
DISPLAY 0.872340 (-1620 3630);
PAINT GREEN (-1620 3630);
DISPLAY INVISIBLE (-1620 3630);
FORCEPROP 2 LAST CDS_LIB mstr_standard
J 0
(-1575 3725);
PAINT ORANGE (-1575 3725);
DISPLAY INVISIBLE (-1575 3725);
FORCEPROP 2 LAST PATH I13
J 0
(-1400 3800);
DISPLAY 1.021277 (-1400 3800);
PAINT ORANGE (-1400 3800);
DISPLAY INVISIBLE (-1400 3800);
FORCEPROP 1 LAST OFFPAGE TRUE
J 0
(-1250 3600);
DISPLAY 0.872340 (-1250 3600);
PAINT GREEN (-1250 3600);
DISPLAY INVISIBLE (-1250 3600);
FORCEADD RES..1
(-2450 4075);
FORCEPROP 1 LAST VALUE 33.2
J 2
(-2500 4025);
DISPLAY 0.617021 (-2500 4025);
PAINT SKYBLUE (-2500 4025);
FORCEPROP 1 LAST TOLERANCE 1%
J 0
(-2475 4025);
DISPLAY 0.617021 (-2475 4025);
PAINT SKYBLUE (-2475 4025);
FORCEPROP 1 LAST WATTAGE 1/16W
J 2
(-2250 4025);
DISPLAY 0.617021 (-2250 4025);
PAINT SKYBLUE (-2250 4025);
FORCEPROP 1 LAST PART_NUMBER G21796-074
J 0
(-2225 4025);
DISPLAY 0.617021 (-2225 4025);
PAINT BLUE (-2225 4025);
FORCEPROP 1 LAST PACK_TYPE 0402
J 0
(-2000 4025);
DISPLAY 0.617021 (-2000 4025);
PAINT SKYBLUE (-2000 4025);
FORCEPROP 1 LAST MATERIAL CHIP
J 0
(-1900 4025);
DISPLAY 0.617021 (-1900 4025);
PAINT SKYBLUE (-1900 4025);
FORCEPROP 1 LASTPIN (-2550 4075) $PN 1
J 0
(-2538 4087);
DISPLAY 0.617021 (-2538 4087);
PAINT ORANGE (-2538 4087);
FORCEPROP 1 LASTPIN (-2350 4075) $PN 2
J 0
(-2388 4087);
DISPLAY 0.617021 (-2388 4087);
PAINT ORANGE (-2388 4087);
FORCEPROP 1 LAST LOCATION R9G31
J 0
(-2500 4125);
DISPLAY 0.617021 (-2500 4125);
PAINT AQUA (-2500 4125);
FORCEPROP 2 LAST CDS_LIB mstr_discrete
J 0
(-2450 4075);
PAINT ORANGE (-2450 4075);
DISPLAY INVISIBLE (-2450 4075);
FORCEPROP 2 LAST ROOM PROC_SIDEBAND
J 0
(-2500 4175);
DISPLAY 1.021277 (-2500 4175);
PAINT ORANGE (-2500 4175);
DISPLAY INVISIBLE (-2500 4175);
FORCEPROP 2 LAST SEC_TYPE 0402
J 0
(-2500 4275);
DISPLAY 1.021277 (-2500 4275);
PAINT ORANGE (-2500 4275);
DISPLAY INVISIBLE (-2500 4275);
FORCEPROP 2 LAST BOM_COST PROC_SIDEBAND
J 0
(-2500 4225);
DISPLAY 1.021277 (-2500 4225);
PAINT ORANGE (-2500 4225);
DISPLAY INVISIBLE (-2500 4225);
FORCEPROP 2 LAST SEC 1
J 0
(-2500 4275);
DISPLAY 0.680851 (-2500 4275);
PAINT MONO (-2500 4275);
DISPLAY INVISIBLE (-2500 4275);
FORCEPROP 1 LAST PATH I14
J 0
(-2500 4225);
DISPLAY 0.978723 (-2500 4225);
PAINT WHITE (-2500 4225);
DISPLAY INVISIBLE (-2500 4225);
FORCEADD RES..1
(-2450 3900);
FORCEPROP 1 LAST VALUE 33.2
J 2
(-2500 3850);
DISPLAY 0.617021 (-2500 3850);
PAINT SKYBLUE (-2500 3850);
FORCEPROP 1 LASTPIN (-2550 3900) $PN 1
J 0
(-2538 3912);
DISPLAY 0.617021 (-2538 3912);
PAINT ORANGE (-2538 3912);
FORCEPROP 1 LAST TOLERANCE 1%
J 0
(-2475 3850);
DISPLAY 0.617021 (-2475 3850);
PAINT SKYBLUE (-2475 3850);
FORCEPROP 1 LAST LOCATION R1U36
J 0
(-2500 3950);
DISPLAY 0.617021 (-2500 3950);
PAINT AQUA (-2500 3950);
FORCEPROP 1 LASTPIN (-2350 3900) $PN 2
J 0
(-2388 3912);
DISPLAY 0.617021 (-2388 3912);
PAINT ORANGE (-2388 3912);
FORCEPROP 1 LAST WATTAGE 1/16W
J 2
(-2250 3850);
DISPLAY 0.617021 (-2250 3850);
PAINT SKYBLUE (-2250 3850);
FORCEPROP 1 LAST PART_NUMBER G21796-074
J 0
(-2225 3850);
DISPLAY 0.617021 (-2225 3850);
PAINT BLUE (-2225 3850);
FORCEPROP 1 LAST PACK_TYPE 0402
J 0
(-2000 3850);
DISPLAY 0.617021 (-2000 3850);
PAINT SKYBLUE (-2000 3850);
FORCEPROP 1 LAST MATERIAL CHIP
J 0
(-1900 3850);
DISPLAY 0.617021 (-1900 3850);
PAINT SKYBLUE (-1900 3850);
FORCEPROP 2 LAST CDS_LIB mstr_discrete
J 0
(-2450 3900);
PAINT ORANGE (-2450 3900);
DISPLAY INVISIBLE (-2450 3900);
FORCEPROP 2 LAST CDS_LOCATION R1U36
J 0
(-2500 3950);
DISPLAY 0.617021 (-2500 3950);
PAINT AQUA (-2500 3950);
DISPLAY INVISIBLE (-2500 3950);
FORCEPROP 2 LAST ROOM PROC_SIDEBAND
J 0
(-2500 4000);
DISPLAY 1.021277 (-2500 4000);
PAINT ORANGE (-2500 4000);
DISPLAY INVISIBLE (-2500 4000);
FORCEPROP 1 LAST PATH I15
J 0
(-2500 4050);
DISPLAY 0.978723 (-2500 4050);
PAINT WHITE (-2500 4050);
DISPLAY INVISIBLE (-2500 4050);
FORCEPROP 2 LAST BOM_COST PROC_SIDEBAND
J 0
(-2500 4050);
DISPLAY 1.021277 (-2500 4050);
PAINT ORANGE (-2500 4050);
DISPLAY INVISIBLE (-2500 4050);
FORCEPROP 2 LAST SEC_TYPE 0402
J 0
(-2500 4100);
DISPLAY 1.021277 (-2500 4100);
PAINT ORANGE (-2500 4100);
DISPLAY INVISIBLE (-2500 4100);
FORCEPROP 2 LAST SEC 1
J 0
(-2500 4100);
DISPLAY 0.680851 (-2500 4100);
PAINT MONO (-2500 4100);
DISPLAY INVISIBLE (-2500 4100);
FORCEADD RES..1
(-2450 3725);
FORCEPROP 1 LAST VALUE 33.2
J 2
(-2500 3675);
DISPLAY 0.617021 (-2500 3675);
PAINT SKYBLUE (-2500 3675);
FORCEPROP 1 LASTPIN (-2550 3725) $PN 1
J 0
(-2538 3737);
DISPLAY 0.617021 (-2538 3737);
PAINT ORANGE (-2538 3737);
FORCEPROP 1 LAST TOLERANCE 1%
J 0
(-2475 3675);
DISPLAY 0.617021 (-2475 3675);
PAINT SKYBLUE (-2475 3675);
FORCEPROP 1 LAST LOCATION R1U34
J 0
(-2500 3775);
DISPLAY 0.617021 (-2500 3775);
PAINT AQUA (-2500 3775);
FORCEPROP 1 LASTPIN (-2350 3725) $PN 2
J 0
(-2388 3737);
DISPLAY 0.617021 (-2388 3737);
PAINT ORANGE (-2388 3737);
FORCEPROP 1 LAST WATTAGE 1/16W
J 2
(-2250 3675);
DISPLAY 0.617021 (-2250 3675);
PAINT SKYBLUE (-2250 3675);
FORCEPROP 1 LAST PART_NUMBER G21796-074
J 0
(-2225 3675);
DISPLAY 0.617021 (-2225 3675);
PAINT BLUE (-2225 3675);
FORCEPROP 1 LAST PACK_TYPE 0402
J 0
(-2000 3675);
DISPLAY 0.617021 (-2000 3675);
PAINT SKYBLUE (-2000 3675);
FORCEPROP 1 LAST MATERIAL CHIP
J 0
(-1900 3675);
DISPLAY 0.617021 (-1900 3675);
PAINT SKYBLUE (-1900 3675);
FORCEPROP 2 LAST CDS_LIB mstr_discrete
J 0
(-2450 3725);
PAINT ORANGE (-2450 3725);
DISPLAY INVISIBLE (-2450 3725);
FORCEPROP 2 LAST CDS_LOCATION R1U34
J 0
(-2500 3775);
DISPLAY 0.617021 (-2500 3775);
PAINT AQUA (-2500 3775);
DISPLAY INVISIBLE (-2500 3775);
FORCEPROP 2 LAST ROOM PROC_TRANSLATORS
J 0
(-2500 3825);
DISPLAY 1.021277 (-2500 3825);
PAINT ORANGE (-2500 3825);
DISPLAY INVISIBLE (-2500 3825);
FORCEPROP 1 LAST PATH I16
J 0
(-2500 3875);
DISPLAY 0.978723 (-2500 3875);
PAINT WHITE (-2500 3875);
DISPLAY INVISIBLE (-2500 3875);
FORCEPROP 2 LAST SEC_TYPE 0402
J 0
(-2500 3925);
DISPLAY 1.021277 (-2500 3925);
PAINT ORANGE (-2500 3925);
DISPLAY INVISIBLE (-2500 3925);
FORCEPROP 2 LAST BOM_COST PROC_SIDEBAND
J 0
(-2500 3875);
DISPLAY 1.021277 (-2500 3875);
PAINT ORANGE (-2500 3875);
DISPLAY INVISIBLE (-2500 3875);
FORCEPROP 2 LAST SEC 1
J 0
(-2500 3925);
DISPLAY 0.680851 (-2500 3925);
PAINT MONO (-2500 3925);
DISPLAY INVISIBLE (-2500 3925);
FORCEADD GND..1
(-5900 3525);
FORCEPROP 3 LASTPIN (-5900 3575) SIG_NAME GND\g
J 0
(-5890 3585);
DISPLAY 0.659574 (-5890 3585);
PAINT MONO (-5890 3585);
DISPLAY INVISIBLE (-5890 3585);
FORCEPROP 1 LAST PATH I17
J 0
(-5825 3525);
DISPLAY 0.872340 (-5825 3525);
PAINT AQUA (-5825 3525);
DISPLAY INVISIBLE (-5825 3525);
FORCEPROP 1 LAST BODY_TYPE PLUMBING
J 0
(-5945 3482);
DISPLAY 0.340426 (-5945 3482);
PAINT GREEN (-5945 3482);
DISPLAY INVISIBLE (-5945 3482);
FORCEPROP 1 LAST SIZE 1B
J 0
(-5825 3475);
DISPLAY 0.872340 (-5825 3475);
PAINT AQUA (-5825 3475);
DISPLAY INVISIBLE (-5825 3475);
FORCEPROP 2 LAST CDS_LIB mstr_symbols
J 0
(-5900 3525);
PAINT ORANGE (-5900 3525);
DISPLAY INVISIBLE (-5900 3525);
FORCEPROP 1 LAST VOLTAGE 0.0V
J 0
(-5945 3482);
DISPLAY 0.340426 (-5945 3482);
PAINT SKYBLUE (-5945 3482);
DISPLAY INVISIBLE (-5945 3482);
FORCEPROP 1 LAST HDL_POWER GND
J 0
(-5900 3675);
DISPLAY 0.872340 (-5900 3675);
PAINT GREEN (-5900 3675);
DISPLAY INVISIBLE (-5900 3675);
FORCEADD CAP..1
(-4525 4650);
FORCEPROP 1 LASTPIN (-4525 4550) $PN 2
J 0
(-4515 4530);
DISPLAY 0.617021 (-4515 4530);
PAINT ORANGE (-4515 4530);
FORCEPROP 1 LAST MATERIAL X6S
J 0
(-4475 4550);
DISPLAY 0.617021 (-4475 4550);
PAINT SKYBLUE (-4475 4550);
FORCEPROP 1 LAST PACK_TYPE 0402
J 0
(-4475 4450);
DISPLAY 0.617021 (-4475 4450);
PAINT SKYBLUE (-4475 4450);
FORCEPROP 1 LAST PART_NUMBER D97712-011
J 0
(-4475 4500);
DISPLAY 0.617021 (-4475 4500);
PAINT BLUE (-4475 4500);
FORCEPROP 1 LAST TOLERANCE 10%
J 0
(-4475 4600);
DISPLAY 0.617021 (-4475 4600);
PAINT SKYBLUE (-4475 4600);
FORCEPROP 1 LASTPIN (-4525 4750) $PN 1
J 0
(-4515 4730);
DISPLAY 0.617021 (-4515 4730);
PAINT ORANGE (-4515 4730);
FORCEPROP 1 LAST VOLTAGE 16V
J 0
(-4475 4650);
DISPLAY 0.617021 (-4475 4650);
PAINT SKYBLUE (-4475 4650);
FORCEPROP 1 LAST LOCATION C1U19
J 0
(-4475 4750);
DISPLAY 0.617021 (-4475 4750);
PAINT AQUA (-4475 4750);
FORCEPROP 1 LAST VALUE 1.0UF
J 0
(-4475 4700);
DISPLAY 0.617021 (-4475 4700);
PAINT SKYBLUE (-4475 4700);
FORCEPROP 2 LAST ROOM PROC_SIDEBAND
J 0
(-4475 4800);
DISPLAY 1.021277 (-4475 4800);
PAINT ORANGE (-4475 4800);
DISPLAY INVISIBLE (-4475 4800);
FORCEPROP 1 LAST PATH I18
J 0
(-4475 4800);
DISPLAY 0.978723 (-4475 4800);
PAINT WHITE (-4475 4800);
DISPLAY INVISIBLE (-4475 4800);
FORCEPROP 2 LAST CDS_LOCATION C1U19
J 0
(-4475 4750);
DISPLAY 0.617021 (-4475 4750);
PAINT AQUA (-4475 4750);
DISPLAY INVISIBLE (-4475 4750);
FORCEPROP 2 LAST CDS_LIB mstr_discrete
J 0
(-4525 4650);
PAINT ORANGE (-4525 4650);
DISPLAY INVISIBLE (-4525 4650);
FORCEPROP 2 LAST SEC 1
J 0
(-4475 4850);
PAINT MONO (-4475 4850);
DISPLAY INVISIBLE (-4475 4850);
FORCEPROP 2 LAST BOM_COST PROC_SIDEBAND
J 0
(-4475 4850);
DISPLAY 1.021277 (-4475 4850);
PAINT ORANGE (-4475 4850);
DISPLAY INVISIBLE (-4475 4850);
FORCEPROP 2 LAST SEC_TYPE 0402
J 0
(-4475 4850);
DISPLAY 1.021277 (-4475 4850);
PAINT ORANGE (-4475 4850);
DISPLAY INVISIBLE (-4475 4850);
FORCEADD RES..1
(-4350 4200);
FORCEPROP 1 LAST VALUE 1.00K
J 2
(-4500 4150);
DISPLAY 0.617021 (-4500 4150);
PAINT SKYBLUE (-4500 4150);
FORCEPROP 1 LASTPIN (-4450 4200) $PN 1
J 0
(-4438 4212);
DISPLAY 0.617021 (-4438 4212);
PAINT ORANGE (-4438 4212);
FORCEPROP 1 LAST TOLERANCE 1%
J 0
(-4450 4150);
DISPLAY 0.617021 (-4450 4150);
PAINT SKYBLUE (-4450 4150);
FORCEPROP 1 LAST LOCATION R1U30
J 0
(-4400 4250);
DISPLAY 0.617021 (-4400 4250);
PAINT AQUA (-4400 4250);
FORCEPROP 1 LASTPIN (-4250 4200) $PN 2
J 0
(-4288 4212);
DISPLAY 0.617021 (-4288 4212);
PAINT ORANGE (-4288 4212);
FORCEPROP 1 LAST WATTAGE 1/16W
J 2
(-4175 4150);
DISPLAY 0.617021 (-4175 4150);
PAINT SKYBLUE (-4175 4150);
FORCEPROP 1 LAST PACK_TYPE 0402
J 0
(-4150 4150);
DISPLAY 0.617021 (-4150 4150);
PAINT SKYBLUE (-4150 4150);
FORCEPROP 1 LAST MATERIAL CHIP
J 0
(-4050 4100);
DISPLAY 0.617021 (-4050 4100);
PAINT SKYBLUE (-4050 4100);
FORCEPROP 1 LAST PART_NUMBER G21796-026
J 0
(-4050 4150);
DISPLAY 0.617021 (-4050 4150);
PAINT BLUE (-4050 4150);
FORCEPROP 2 LAST ROOM PROC_TRANSLATORS
J 0
(-4375 4275);
DISPLAY 1.021277 (-4375 4275);
PAINT ORANGE (-4375 4275);
DISPLAY INVISIBLE (-4375 4275);
FORCEPROP 2 LAST CDS_LOCATION R1U30
J 0
(-4400 4250);
DISPLAY 0.617021 (-4400 4250);
PAINT AQUA (-4400 4250);
DISPLAY INVISIBLE (-4400 4250);
FORCEPROP 1 LAST PATH I2
J 0
(-4400 4350);
DISPLAY 0.978723 (-4400 4350);
PAINT WHITE (-4400 4350);
DISPLAY INVISIBLE (-4400 4350);
FORCEPROP 2 LAST BOM_COST PROC_SIDEBAND
J 0
(-4375 4325);
DISPLAY 1.021277 (-4375 4325);
PAINT ORANGE (-4375 4325);
DISPLAY INVISIBLE (-4375 4325);
FORCEPROP 2 LAST SEC_TYPE 0402
J 0
(-4400 4400);
DISPLAY 1.021277 (-4400 4400);
PAINT ORANGE (-4400 4400);
DISPLAY INVISIBLE (-4400 4400);
FORCEPROP 2 LAST SEC 1
J 0
(-4400 4400);
DISPLAY 0.680851 (-4400 4400);
PAINT MONO (-4400 4400);
DISPLAY INVISIBLE (-4400 4400);
FORCEPROP 2 LAST CDS_LIB mstr_discrete
J 0
(-4350 4200);
PAINT ORANGE (-4350 4200);
DISPLAY INVISIBLE (-4350 4200);
FORCEADD GND..1
(-4525 4450);
FORCEPROP 3 LASTPIN (-4525 4500) SIG_NAME GND\g
J 0
(-4515 4510);
DISPLAY 0.659574 (-4515 4510);
PAINT MONO (-4515 4510);
DISPLAY INVISIBLE (-4515 4510);
FORCEPROP 1 LAST BODY_TYPE PLUMBING
J 0
(-4570 4407);
DISPLAY 0.340426 (-4570 4407);
PAINT GREEN (-4570 4407);
DISPLAY INVISIBLE (-4570 4407);
FORCEPROP 1 LAST VOLTAGE 0.0V
J 0
(-4570 4407);
DISPLAY 0.340426 (-4570 4407);
PAINT SKYBLUE (-4570 4407);
DISPLAY INVISIBLE (-4570 4407);
FORCEPROP 2 LAST CDS_LIB mstr_symbols
J 0
(-4525 4450);
PAINT ORANGE (-4525 4450);
DISPLAY INVISIBLE (-4525 4450);
FORCEPROP 1 LAST PATH I20
J 0
(-4450 4450);
DISPLAY 0.872340 (-4450 4450);
PAINT AQUA (-4450 4450);
DISPLAY INVISIBLE (-4450 4450);
FORCEPROP 1 LAST SIZE 1B
J 0
(-4450 4400);
DISPLAY 0.872340 (-4450 4400);
PAINT AQUA (-4450 4400);
DISPLAY INVISIBLE (-4450 4400);
FORCEPROP 1 LAST HDL_POWER GND
J 0
(-4525 4600);
DISPLAY 0.872340 (-4525 4600);
PAINT GREEN (-4525 4600);
DISPLAY INVISIBLE (-4525 4600);
FORCEADD OFFPAGE..1
(-8525 4225);
FORCEPROP 2 LAST $XR0 94 
J 0
(-8776 4225);
DISPLAY 0.638298 (-8776 4225);
PAINT MONO (-8776 4225);
FORCEPROP 2 LAST $XR1 95 
J 0
(-8866 4225);
DISPLAY 0.638298 (-8866 4225);
PAINT MONO (-8866 4225);
FORCEPROP 2 LAST $XR2 21 
J 0
(-8956 4225);
DISPLAY 0.638298 (-8956 4225);
PAINT MONO (-8956 4225);
FORCEPROP 2 LAST PATH I21
J 0
(-8475 4300);
DISPLAY 1.021277 (-8475 4300);
PAINT ORANGE (-8475 4300);
DISPLAY INVISIBLE (-8475 4300);
FORCEPROP 2 LAST CDS_LIB mstr_standard
J 0
(-8525 4225);
PAINT ORANGE (-8525 4225);
DISPLAY INVISIBLE (-8525 4225);
FORCEPROP 1 LAST COMMENT_BODY TRUE
J 0
(-8400 4125);
DISPLAY 0.872340 (-8400 4125);
PAINT GREEN (-8400 4125);
DISPLAY INVISIBLE (-8400 4125);
FORCEPROP 1 LAST OFFPAGE TRUE
J 0
(-8200 4100);
DISPLAY 0.872340 (-8200 4100);
PAINT GREEN (-8200 4100);
DISPLAY INVISIBLE (-8200 4100);
FORCEADD OFFPAGE..1
(-8525 4050);
FORCEPROP 2 LAST $XR0 94 
J 0
(-8776 4050);
DISPLAY 0.638298 (-8776 4050);
PAINT MONO (-8776 4050);
FORCEPROP 2 LAST $XR1 95 
J 0
(-8866 4050);
DISPLAY 0.638298 (-8866 4050);
PAINT MONO (-8866 4050);
FORCEPROP 2 LAST $XR2 21 
J 0
(-8956 4050);
DISPLAY 0.638298 (-8956 4050);
PAINT MONO (-8956 4050);
FORCEPROP 2 LAST CDS_LIB mstr_standard
J 0
(-8525 4050);
PAINT ORANGE (-8525 4050);
DISPLAY INVISIBLE (-8525 4050);
FORCEPROP 1 LAST COMMENT_BODY TRUE
J 0
(-8400 3950);
DISPLAY 0.872340 (-8400 3950);
PAINT GREEN (-8400 3950);
DISPLAY INVISIBLE (-8400 3950);
FORCEPROP 1 LAST OFFPAGE TRUE
J 0
(-8200 3925);
DISPLAY 0.872340 (-8200 3925);
PAINT GREEN (-8200 3925);
DISPLAY INVISIBLE (-8200 3925);
FORCEPROP 2 LAST PATH I22
J 0
(-8475 4125);
DISPLAY 1.021277 (-8475 4125);
PAINT ORANGE (-8475 4125);
DISPLAY INVISIBLE (-8475 4125);
FORCEADD OFFPAGE..1
(-8525 3900);
FORCEPROP 2 LAST $XR0 55 
J 0
(-8776 3900);
DISPLAY 0.638298 (-8776 3900);
PAINT MONO (-8776 3900);
FORCEPROP 2 LAST $XR1 94 
J 0
(-8866 3900);
DISPLAY 0.638298 (-8866 3900);
PAINT MONO (-8866 3900);
FORCEPROP 2 LAST $XR2 95 
J 0
(-8956 3900);
DISPLAY 0.638298 (-8956 3900);
PAINT MONO (-8956 3900);
FORCEPROP 2 LAST CDS_LIB mstr_standard
J 0
(-8525 3900);
PAINT ORANGE (-8525 3900);
DISPLAY INVISIBLE (-8525 3900);
FORCEPROP 2 LAST PATH I23
J 0
(-8475 3975);
DISPLAY 1.021277 (-8475 3975);
PAINT ORANGE (-8475 3975);
DISPLAY INVISIBLE (-8475 3975);
FORCEPROP 1 LAST COMMENT_BODY TRUE
J 0
(-8400 3800);
DISPLAY 0.872340 (-8400 3800);
PAINT GREEN (-8400 3800);
DISPLAY INVISIBLE (-8400 3800);
FORCEPROP 1 LAST OFFPAGE TRUE
J 0
(-8200 3775);
DISPLAY 0.872340 (-8200 3775);
PAINT GREEN (-8200 3775);
DISPLAY INVISIBLE (-8200 3775);
FORCEADD OFFPAGE..1
(-8525 3750);
FORCEPROP 2 LAST $XR0 55 
J 0
(-8776 3750);
DISPLAY 0.638298 (-8776 3750);
PAINT MONO (-8776 3750);
FORCEPROP 2 LAST $XR1 94 
J 0
(-8866 3750);
DISPLAY 0.638298 (-8866 3750);
PAINT MONO (-8866 3750);
FORCEPROP 2 LAST $XR2 95 
J 0
(-8956 3750);
DISPLAY 0.638298 (-8956 3750);
PAINT MONO (-8956 3750);
FORCEPROP 2 LAST CDS_LIB mstr_standard
J 0
(-8525 3750);
PAINT ORANGE (-8525 3750);
DISPLAY INVISIBLE (-8525 3750);
FORCEPROP 2 LAST PATH I24
J 0
(-8475 3825);
DISPLAY 1.021277 (-8475 3825);
PAINT ORANGE (-8475 3825);
DISPLAY INVISIBLE (-8475 3825);
FORCEPROP 1 LAST COMMENT_BODY TRUE
J 0
(-8400 3650);
DISPLAY 0.872340 (-8400 3650);
PAINT GREEN (-8400 3650);
DISPLAY INVISIBLE (-8400 3650);
FORCEPROP 1 LAST OFFPAGE TRUE
J 0
(-8200 3625);
DISPLAY 0.872340 (-8200 3625);
PAINT GREEN (-8200 3625);
DISPLAY INVISIBLE (-8200 3625);
FORCEADD RES..2
(-1775 2000);
FORCEPROP 1 LAST WATTAGE 1/16W
J 0
(-1735 1975);
DISPLAY 0.617021 (-1735 1975);
PAINT SKYBLUE (-1735 1975);
FORCEPROP 1 LAST MATERIAL CHIP
J 0
(-1735 1925);
DISPLAY 0.617021 (-1735 1925);
PAINT SKYBLUE (-1735 1925);
FORCEPROP 1 LAST PACK_TYPE 0402
J 0
(-1735 1825);
DISPLAY 0.617021 (-1735 1825);
PAINT SKYBLUE (-1735 1825);
FORCEPROP 1 LAST PART_NUMBER G21796-047
J 0
(-1735 1875);
DISPLAY 0.617021 (-1735 1875);
PAINT BLUE (-1735 1875);
FORCEPROP 1 LAST TOLERANCE 1%
J 0
(-1730 2025);
DISPLAY 0.617021 (-1730 2025);
PAINT SKYBLUE (-1730 2025);
FORCEPROP 1 LAST VALUE 49.9
J 0
(-1730 2075);
DISPLAY 0.617021 (-1730 2075);
PAINT SKYBLUE (-1730 2075);
FORCEPROP 1 LAST LOCATION R1U43
J 0
(-1730 2125);
DISPLAY 0.617021 (-1730 2125);
PAINT AQUA (-1730 2125);
FORCEPROP 1 LASTPIN (-1775 1900) $PN 2
J 0
(-1770 1910);
DISPLAY 0.787234 (-1770 1910);
PAINT ORANGE (-1770 1910);
DISPLAY INVISIBLE (-1770 1910);
FORCEPROP 2 LAST CDS_LIB mstr_discrete
J 0
(-1775 2000);
PAINT ORANGE (-1775 2000);
DISPLAY INVISIBLE (-1775 2000);
FORCEPROP 2 LAST BOM_COST PROC_SIDEBAND
J 0
(-1725 2225);
DISPLAY 1.021277 (-1725 2225);
PAINT ORANGE (-1725 2225);
DISPLAY INVISIBLE (-1725 2225);
FORCEPROP 2 LAST CDS_SEC 1
J 0
(-1725 2225);
PAINT MONO (-1725 2225);
DISPLAY INVISIBLE (-1725 2225);
FORCEPROP 2 LAST CDS_LOCATION R1U43
J 0
(-1730 2125);
DISPLAY 0.617021 (-1730 2125);
PAINT AQUA (-1730 2125);
DISPLAY INVISIBLE (-1730 2125);
FORCEPROP 2 LAST $SEC 1
J 0
(-1725 2225);
PAINT MONO (-1725 2225);
DISPLAY INVISIBLE (-1725 2225);
FORCEPROP 2 LAST ROOM PROC_SIDEBAND
J 0
(-1725 2175);
DISPLAY 1.021277 (-1725 2175);
PAINT ORANGE (-1725 2175);
DISPLAY INVISIBLE (-1725 2175);
FORCEPROP 1 LAST PATH I25
J 0
(-1725 2175);
DISPLAY 0.978723 (-1725 2175);
PAINT WHITE (-1725 2175);
DISPLAY INVISIBLE (-1725 2175);
FORCEPROP 1 LASTPIN (-1775 2100) $PN 1
J 0
(-1770 2062);
DISPLAY 0.787234 (-1770 2062);
PAINT ORANGE (-1770 2062);
DISPLAY INVISIBLE (-1770 2062);
FORCEADD RES..2
(-1775 1600);
FORCEPROP 1 LAST PACK_TYPE 0402
J 0
(-1735 1425);
DISPLAY 0.617021 (-1735 1425);
PAINT SKYBLUE (-1735 1425);
FORCEPROP 1 LAST MATERIAL CHIP
J 0
(-1735 1525);
DISPLAY 0.617021 (-1735 1525);
PAINT SKYBLUE (-1735 1525);
FORCEPROP 1 LAST TOLERANCE 1%
J 0
(-1730 1625);
DISPLAY 0.617021 (-1730 1625);
PAINT SKYBLUE (-1730 1625);
FORCEPROP 1 LAST LOCATION R1U37
J 0
(-1730 1725);
DISPLAY 0.617021 (-1730 1725);
PAINT AQUA (-1730 1725);
FORCEPROP 1 LAST VALUE 100.0
J 0
(-1730 1675);
DISPLAY 0.617021 (-1730 1675);
PAINT SKYBLUE (-1730 1675);
FORCEPROP 1 LAST WATTAGE 1/16W
J 0
(-1735 1575);
DISPLAY 0.617021 (-1735 1575);
PAINT SKYBLUE (-1735 1575);
FORCEPROP 1 LAST PART_NUMBER G21796-017
J 0
(-1735 1475);
DISPLAY 0.617021 (-1735 1475);
PAINT BLUE (-1735 1475);
FORCEPROP 1 LASTPIN (-1775 1500) $PN 2
J 0
(-1770 1510);
DISPLAY 0.787234 (-1770 1510);
PAINT ORANGE (-1770 1510);
DISPLAY INVISIBLE (-1770 1510);
FORCEPROP 2 LAST CDS_LIB mstr_discrete
J 0
(-1775 1600);
PAINT ORANGE (-1775 1600);
DISPLAY INVISIBLE (-1775 1600);
FORCEPROP 2 LAST CDS_LOCATION R1U37
J 0
(-1730 1725);
DISPLAY 0.617021 (-1730 1725);
PAINT AQUA (-1730 1725);
DISPLAY INVISIBLE (-1730 1725);
FORCEPROP 1 LASTPIN (-1775 1700) $PN 1
J 0
(-1770 1662);
DISPLAY 0.787234 (-1770 1662);
PAINT ORANGE (-1770 1662);
DISPLAY INVISIBLE (-1770 1662);
FORCEPROP 2 LAST ROOM PROC_SIDEBAND
J 0
(-1725 1775);
DISPLAY 1.021277 (-1725 1775);
PAINT ORANGE (-1725 1775);
DISPLAY INVISIBLE (-1725 1775);
FORCEPROP 1 LAST PATH I26
J 0
(-1725 1775);
DISPLAY 0.978723 (-1725 1775);
PAINT WHITE (-1725 1775);
DISPLAY INVISIBLE (-1725 1775);
FORCEPROP 2 LAST $SEC 1
J 0
(-1725 1825);
PAINT MONO (-1725 1825);
DISPLAY INVISIBLE (-1725 1825);
FORCEPROP 2 LAST CDS_SEC 1
J 0
(-1725 1825);
PAINT MONO (-1725 1825);
DISPLAY INVISIBLE (-1725 1825);
FORCEPROP 2 LAST BOM_COST PROC_SIDEBAND
J 0
(-1725 1825);
DISPLAY 1.021277 (-1725 1825);
PAINT ORANGE (-1725 1825);
DISPLAY INVISIBLE (-1725 1825);
FORCEADD CAP_A..1
(-2150 1600);
FORCEPROP 1 LAST MATERIAL X7R
J 0
(-2100 1500);
DISPLAY 0.617021 (-2100 1500);
PAINT SKYBLUE (-2100 1500);
FORCEPROP 1 LAST VOLTAGE 16V
J 0
(-2100 1600);
DISPLAY 0.617021 (-2100 1600);
PAINT SKYBLUE (-2100 1600);
FORCEPROP 1 LAST PACK_TYPE 0402V
J 0
(-2100 1400);
DISPLAY 0.617021 (-2100 1400);
PAINT SKYBLUE (-2100 1400);
FORCEPROP 1 LAST TOLERANCE 10%
J 0
(-2100 1550);
DISPLAY 0.617021 (-2100 1550);
PAINT SKYBLUE (-2100 1550);
FORCEPROP 1 LAST VALUE 0.1UF
J 0
(-2100 1650);
DISPLAY 0.617021 (-2100 1650);
PAINT SKYBLUE (-2100 1650);
FORCEPROP 1 LAST PART_NUMBER A36096-030
J 0
(-2100 1450);
DISPLAY 0.617021 (-2100 1450);
PAINT BLUE (-2100 1450);
FORCEPROP 1 LAST LOCATION C1U22
J 0
(-2100 1700);
DISPLAY 0.617021 (-2100 1700);
PAINT AQUA (-2100 1700);
FORCEPROP 1 LASTPIN (-2150 1500) $PN 2
J 0
(-2140 1480);
DISPLAY 0.787234 (-2140 1480);
PAINT ORANGE (-2140 1480);
DISPLAY INVISIBLE (-2140 1480);
FORCEPROP 2 LAST CDS_LIB dev_discrete
J 0
(-2150 1600);
PAINT ORANGE (-2150 1600);
DISPLAY INVISIBLE (-2150 1600);
FORCEPROP 2 LAST CDS_LOCATION C1U22
J 0
(-2100 1700);
DISPLAY 0.617021 (-2100 1700);
PAINT AQUA (-2100 1700);
DISPLAY INVISIBLE (-2100 1700);
FORCEPROP 1 LAST PATH I27
J 0
(-2100 1750);
DISPLAY 0.978723 (-2100 1750);
PAINT WHITE (-2100 1750);
DISPLAY INVISIBLE (-2100 1750);
FORCEPROP 1 LASTPIN (-2150 1700) $PN 1
J 0
(-2140 1680);
DISPLAY 0.787234 (-2140 1680);
PAINT ORANGE (-2140 1680);
DISPLAY INVISIBLE (-2140 1680);
FORCEPROP 2 LAST ROOM PROC_SIDEBAND
J 0
(-2100 1750);
DISPLAY 1.021277 (-2100 1750);
PAINT ORANGE (-2100 1750);
DISPLAY INVISIBLE (-2100 1750);
FORCEPROP 2 LAST BOM_COST PROC_SIDEBAND
J 0
(-2100 1800);
DISPLAY 1.021277 (-2100 1800);
PAINT ORANGE (-2100 1800);
DISPLAY INVISIBLE (-2100 1800);
FORCEPROP 2 LAST CDS_SEC 1
J 0
(-2100 1800);
PAINT MONO (-2100 1800);
DISPLAY INVISIBLE (-2100 1800);
FORCEPROP 2 LAST $SEC 1
J 0
(-2100 1800);
PAINT MONO (-2100 1800);
DISPLAY INVISIBLE (-2100 1800);
FORCEADD PVCCIO_CPU0..1
(-1775 2350);
FORCEPROP 3 LASTPIN (-1775 2300) SIG_NAME PVCCIO_CPU0\g
J 0
(-1765 2310);
DISPLAY 0.659574 (-1765 2310);
PAINT MONO (-1765 2310);
DISPLAY INVISIBLE (-1765 2310);
FORCEPROP 1 LAST VOLTAGE 1.1V
J 0
(-1820 2307);
DISPLAY 0.340426 (-1820 2307);
PAINT SKYBLUE (-1820 2307);
DISPLAY INVISIBLE (-1820 2307);
FORCEPROP 1 LAST BODY_TYPE PLUMBING
J 0
(-1820 2307);
DISPLAY 0.340426 (-1820 2307);
PAINT GREEN (-1820 2307);
DISPLAY INVISIBLE (-1820 2307);
FORCEPROP 1 LAST HDL_POWER PVCCIO_CPU0
J 1
(-1775 2400);
DISPLAY 0.872340 (-1775 2400);
PAINT GREEN (-1775 2400);
DISPLAY INVISIBLE (-1775 2400);
FORCEPROP 1 LAST PATH I28
J 0
(-1725 2375);
DISPLAY 0.872340 (-1725 2375);
PAINT AQUA (-1725 2375);
DISPLAY INVISIBLE (-1725 2375);
FORCEPROP 2 LAST CDS_LIB mstr_symbols
J 0
(-1775 2350);
PAINT ORANGE (-1775 2350);
DISPLAY INVISIBLE (-1775 2350);
FORCEADD GND..1
(-1775 1275);
FORCEPROP 3 LASTPIN (-1775 1325) SIG_NAME GND\g
J 0
(-1765 1335);
DISPLAY 0.659574 (-1765 1335);
PAINT MONO (-1765 1335);
DISPLAY INVISIBLE (-1765 1335);
FORCEPROP 1 LAST VOLTAGE 0.0V
J 0
(-1820 1232);
DISPLAY 0.340426 (-1820 1232);
PAINT SKYBLUE (-1820 1232);
DISPLAY INVISIBLE (-1820 1232);
FORCEPROP 1 LAST BODY_TYPE PLUMBING
J 0
(-1820 1232);
DISPLAY 0.340426 (-1820 1232);
PAINT GREEN (-1820 1232);
DISPLAY INVISIBLE (-1820 1232);
FORCEPROP 1 LAST SIZE 1B
J 0
(-1700 1225);
DISPLAY 0.872340 (-1700 1225);
PAINT AQUA (-1700 1225);
DISPLAY INVISIBLE (-1700 1225);
FORCEPROP 1 LAST PATH I29
J 0
(-1700 1275);
DISPLAY 0.872340 (-1700 1275);
PAINT AQUA (-1700 1275);
DISPLAY INVISIBLE (-1700 1275);
FORCEPROP 2 LAST CDS_LIB mstr_symbols
J 0
(-1775 1275);
PAINT ORANGE (-1775 1275);
DISPLAY INVISIBLE (-1775 1275);
FORCEPROP 1 LAST HDL_POWER GND
J 0
(-1775 1425);
DISPLAY 0.872340 (-1775 1425);
PAINT GREEN (-1775 1425);
DISPLAY INVISIBLE (-1775 1425);
FORCEADD GND..1
(-3825 4125);
FORCEPROP 3 LASTPIN (-3825 4175) SIG_NAME GND\g
J 0
(-3815 4185);
DISPLAY 0.659574 (-3815 4185);
PAINT MONO (-3815 4185);
DISPLAY INVISIBLE (-3815 4185);
FORCEPROP 1 LAST BODY_TYPE PLUMBING
J 0
(-3870 4082);
DISPLAY 0.340426 (-3870 4082);
PAINT GREEN (-3870 4082);
DISPLAY INVISIBLE (-3870 4082);
FORCEPROP 1 LAST SIZE 1B
J 0
(-3750 4075);
DISPLAY 0.872340 (-3750 4075);
PAINT AQUA (-3750 4075);
DISPLAY INVISIBLE (-3750 4075);
FORCEPROP 1 LAST VOLTAGE 0.0V
J 0
(-3870 4082);
DISPLAY 0.340426 (-3870 4082);
PAINT SKYBLUE (-3870 4082);
DISPLAY INVISIBLE (-3870 4082);
FORCEPROP 1 LAST HDL_POWER GND
J 0
(-3825 4275);
DISPLAY 0.872340 (-3825 4275);
PAINT GREEN (-3825 4275);
DISPLAY INVISIBLE (-3825 4275);
FORCEPROP 1 LAST PATH I3
J 0
(-3750 4125);
DISPLAY 0.872340 (-3750 4125);
PAINT AQUA (-3750 4125);
DISPLAY INVISIBLE (-3750 4125);
FORCEPROP 2 LAST CDS_LIB mstr_symbols
J 0
(-3825 4125);
PAINT ORANGE (-3825 4125);
DISPLAY INVISIBLE (-3825 4125);
FORCEADD OFFPAGE..5
(-2650 1800);
FORCEPROP 2 LAST $XR0 152 
J 0
(-2935 1800);
DISPLAY 0.638298 (-2935 1800);
PAINT MONO (-2935 1800);
FORCEPROP 2 LAST PATH I30
J 0
(-2600 1875);
DISPLAY 1.021277 (-2600 1875);
PAINT ORANGE (-2600 1875);
DISPLAY INVISIBLE (-2600 1875);
FORCEPROP 2 LAST CDS_LIB mstr_standard
J 0
(-2650 1800);
PAINT ORANGE (-2650 1800);
DISPLAY INVISIBLE (-2650 1800);
FORCEPROP 1 LAST COMMENT_BODY TRUE
J 0
(-2550 1725);
DISPLAY 0.872340 (-2550 1725);
PAINT GREEN (-2550 1725);
DISPLAY INVISIBLE (-2550 1725);
FORCEPROP 1 LAST OFFPAGE TRUE
J 0
(-2325 1675);
DISPLAY 0.872340 (-2325 1675);
PAINT GREEN (-2325 1675);
DISPLAY INVISIBLE (-2325 1675);
FORCEADD OFFPAGE..4
(-4100 4300);
FORCEPROP 2 LAST $XR0 152 
J 0
(-3914 4300);
DISPLAY 0.638298 (-3914 4300);
PAINT MONO (-3914 4300);
FORCEPROP 1 LAST COMMENT_BODY TRUE
J 0
(-4125 4200);
DISPLAY 0.872340 (-4125 4200);
PAINT GREEN (-4125 4200);
DISPLAY INVISIBLE (-4125 4200);
FORCEPROP 2 LAST CDS_LIB mstr_standard
J 0
(-4100 4300);
PAINT ORANGE (-4100 4300);
DISPLAY INVISIBLE (-4100 4300);
FORCEPROP 2 LAST PATH I4
J 0
(-4050 4375);
DISPLAY 1.021277 (-4050 4375);
PAINT ORANGE (-4050 4375);
DISPLAY INVISIBLE (-4050 4375);
FORCEPROP 1 LAST OFFPAGE TRUE
J 0
(-3775 4175);
DISPLAY 0.872340 (-3775 4175);
PAINT GREEN (-3775 4175);
DISPLAY INVISIBLE (-3775 4175);
FORCEADD RES..1
(-6950 4225);
FORCEPROP 1 LAST VALUE 0.0
J 2
(-7050 4225);
DISPLAY 0.617021 (-7050 4225);
PAINT SKYBLUE (-7050 4225);
FORCEPROP 1 LASTPIN (-7050 4225) $PN 1
J 0
(-7038 4237);
DISPLAY 0.617021 (-7038 4237);
PAINT ORANGE (-7038 4237);
FORCEPROP 1 LAST PART_NUMBER G21497-005
J 0
(-7150 4175);
DISPLAY 0.617021 (-7150 4175);
PAINT BLUE (-7150 4175);
FORCEPROP 1 LAST LOCATION R9G34
J 0
(-7000 4275);
DISPLAY 0.617021 (-7000 4275);
PAINT AQUA (-7000 4275);
FORCEPROP 1 LASTPIN (-6850 4225) $PN 2
J 0
(-6888 4237);
DISPLAY 0.617021 (-6888 4237);
PAINT ORANGE (-6888 4237);
FORCEPROP 1 LAST MATERIAL CHIP
J 0
(-6875 4175);
DISPLAY 0.617021 (-6875 4175);
PAINT SKYBLUE (-6875 4175);
FORCEPROP 1 LAST WATTAGE 1/16W
J 2
(-6975 4075);
DISPLAY 0.617021 (-6975 4075);
PAINT SKYBLUE (-6975 4075);
DISPLAY INVISIBLE (-6975 4075);
FORCEPROP 1 LAST PACK_TYPE 0402
J 0
(-6700 4075);
DISPLAY 0.617021 (-6700 4075);
PAINT SKYBLUE (-6700 4075);
DISPLAY INVISIBLE (-6700 4075);
FORCEPROP 1 LAST TOLERANCE 5%
J 0
(-6950 4125);
DISPLAY 0.617021 (-6950 4125);
PAINT SKYBLUE (-6950 4125);
DISPLAY INVISIBLE (-6950 4125);
FORCEPROP 2 LAST CDS_LIB mstr_discrete
J 0
(-6950 4225);
PAINT ORANGE (-6950 4225);
DISPLAY INVISIBLE (-6950 4225);
FORCEPROP 1 LAST PATH I45
J 0
(-7000 4375);
DISPLAY 0.978723 (-7000 4375);
PAINT WHITE (-7000 4375);
DISPLAY INVISIBLE (-7000 4375);
FORCEPROP 2 LAST SEC 1
J 0
(-7000 4425);
DISPLAY 0.680851 (-7000 4425);
PAINT MONO (-7000 4425);
DISPLAY INVISIBLE (-7000 4425);
FORCEPROP 2 LAST SEC_TYPE 0402
J 0
(-7000 4425);
DISPLAY 1.021277 (-7000 4425);
PAINT ORANGE (-7000 4425);
DISPLAY INVISIBLE (-7000 4425);
FORCEADD RES..2
(-3150 4600);
FORCEPROP 1 LASTPIN (-3150 4500) $PN 2
J 0
(-3145 4510);
DISPLAY 0.617021 (-3145 4510);
PAINT ORANGE (-3145 4510);
FORCEPROP 1 LASTPIN (-3150 4700) $PN 1
J 0
(-3145 4662);
DISPLAY 0.617021 (-3145 4662);
PAINT ORANGE (-3145 4662);
FORCEPROP 1 LAST WATTAGE 1/16W
J 0
(-3110 4575);
DISPLAY 0.617021 (-3110 4575);
PAINT SKYBLUE (-3110 4575);
FORCEPROP 1 LAST PACK_TYPE 0402
J 0
(-3110 4425);
DISPLAY 0.617021 (-3110 4425);
PAINT SKYBLUE (-3110 4425);
FORCEPROP 1 LAST TOLERANCE 5%
J 0
(-3105 4625);
DISPLAY 0.617021 (-3105 4625);
PAINT SKYBLUE (-3105 4625);
FORCEPROP 1 LAST VALUE 0.0
J 0
(-3105 4675);
DISPLAY 0.617021 (-3105 4675);
PAINT SKYBLUE (-3105 4675);
FORCEPROP 1 LAST PART_NUMBER G21497-005
J 0
(-3110 4475);
DISPLAY 0.617021 (-3110 4475);
PAINT BLUE (-3110 4475);
FORCEPROP 1 LAST LOCATION R9G27
J 0
(-3105 4725);
DISPLAY 0.617021 (-3105 4725);
PAINT AQUA (-3105 4725);
FORCEPROP 1 LAST MATERIAL EMPTY
J 0
(-3110 4525);
DISPLAY 0.617021 (-3110 4525);
PAINT RED (-3110 4525);
FORCEPROP 2 LAST CDS_LIB mstr_discrete
J 0
(-3150 4600);
PAINT ORANGE (-3150 4600);
DISPLAY INVISIBLE (-3150 4600);
FORCEPROP 1 LAST PATH I47
J 0
(-3100 4775);
DISPLAY 0.978723 (-3100 4775);
PAINT WHITE (-3100 4775);
DISPLAY INVISIBLE (-3100 4775);
FORCEPROP 2 LAST SEC 1
J 0
(-3100 4825);
DISPLAY 0.680851 (-3100 4825);
PAINT MONO (-3100 4825);
DISPLAY INVISIBLE (-3100 4825);
FORCEPROP 2 LAST SEC_TYPE 0402
J 0
(-3100 4825);
DISPLAY 1.021277 (-3100 4825);
PAINT ORANGE (-3100 4825);
DISPLAY INVISIBLE (-3100 4825);
FORCEADD RES..1
(-6950 4050);
FORCEPROP 1 LAST VALUE 0.0
J 2
(-7050 4050);
DISPLAY 0.617021 (-7050 4050);
PAINT SKYBLUE (-7050 4050);
FORCEPROP 1 LASTPIN (-7050 4050) $PN 1
J 0
(-7038 4062);
DISPLAY 0.617021 (-7038 4062);
PAINT ORANGE (-7038 4062);
FORCEPROP 1 LAST PART_NUMBER G21497-005
J 0
(-7150 4000);
DISPLAY 0.617021 (-7150 4000);
PAINT BLUE (-7150 4000);
FORCEPROP 1 LASTPIN (-6850 4050) $PN 2
J 0
(-6888 4062);
DISPLAY 0.617021 (-6888 4062);
PAINT ORANGE (-6888 4062);
FORCEPROP 1 LAST MATERIAL CHIP
J 0
(-6875 4000);
DISPLAY 0.617021 (-6875 4000);
PAINT SKYBLUE (-6875 4000);
FORCEPROP 1 LAST LOCATION R1U58
J 0
(-7000 4100);
DISPLAY 0.617021 (-7000 4100);
PAINT AQUA (-7000 4100);
FORCEPROP 1 LAST WATTAGE 1/16W
J 2
(-6975 3900);
DISPLAY 0.617021 (-6975 3900);
PAINT SKYBLUE (-6975 3900);
DISPLAY INVISIBLE (-6975 3900);
FORCEPROP 1 LAST TOLERANCE 5%
J 0
(-6950 3950);
DISPLAY 0.617021 (-6950 3950);
PAINT SKYBLUE (-6950 3950);
DISPLAY INVISIBLE (-6950 3950);
FORCEPROP 2 LAST CDS_LIB mstr_discrete
J 0
(-6950 4050);
PAINT ORANGE (-6950 4050);
DISPLAY INVISIBLE (-6950 4050);
FORCEPROP 1 LAST PACK_TYPE 0402
J 0
(-6700 3900);
DISPLAY 0.617021 (-6700 3900);
PAINT SKYBLUE (-6700 3900);
DISPLAY INVISIBLE (-6700 3900);
FORCEPROP 1 LAST PATH I49
J 0
(-7000 4200);
DISPLAY 0.978723 (-7000 4200);
PAINT WHITE (-7000 4200);
DISPLAY INVISIBLE (-7000 4200);
FORCEPROP 2 LAST SEC 1
J 0
(-7000 4250);
DISPLAY 0.680851 (-7000 4250);
PAINT MONO (-7000 4250);
DISPLAY INVISIBLE (-7000 4250);
FORCEPROP 2 LAST SEC_TYPE 0402
J 0
(-7000 4250);
DISPLAY 1.021277 (-7000 4250);
PAINT ORANGE (-7000 4250);
DISPLAY INVISIBLE (-7000 4250);
FORCEADD P3V3..1
(-4775 4925);
FORCEPROP 3 LASTPIN (-4775 4875) SIG_NAME P3V3\g
J 0
(-4765 4885);
DISPLAY 0.659574 (-4765 4885);
PAINT MONO (-4765 4885);
DISPLAY INVISIBLE (-4765 4885);
FORCEPROP 1 LAST HDL_POWER P3V3
J 0
(-5100 4800);
DISPLAY 0.872340 (-5100 4800);
PAINT ORANGE (-5100 4800);
DISPLAY INVISIBLE (-5100 4800);
FORCEPROP 1 LAST PATH I5
J 0
(-4730 4927);
DISPLAY 0.340426 (-4730 4927);
PAINT GREEN (-4730 4927);
DISPLAY INVISIBLE (-4730 4927);
FORCEPROP 1 LAST BODY_TYPE PLUMBING
J 0
(-4820 4882);
DISPLAY 0.340426 (-4820 4882);
PAINT GREEN (-4820 4882);
DISPLAY INVISIBLE (-4820 4882);
FORCEPROP 1 LAST SIZE 1B
J 0
(-4730 4947);
DISPLAY 0.340426 (-4730 4947);
PAINT GREEN (-4730 4947);
DISPLAY INVISIBLE (-4730 4947);
FORCEPROP 2 LAST CDS_LIB mstr_symbols
J 0
(-4775 4925);
PAINT ORANGE (-4775 4925);
DISPLAY INVISIBLE (-4775 4925);
FORCEPROP 1 LAST VOLTAGE 3.3V
J 0
(-4820 4882);
DISPLAY 0.340426 (-4820 4882);
PAINT SKYBLUE (-4820 4882);
DISPLAY INVISIBLE (-4820 4882);
FORCEADD RES..2
(-7175 4525);
FORCEPROP 1 LASTPIN (-7175 4625) $PN 1
J 0
(-7170 4587);
DISPLAY 0.617021 (-7170 4587);
PAINT ORANGE (-7170 4587);
FORCEPROP 1 LASTPIN (-7175 4425) $PN 2
J 0
(-7170 4435);
DISPLAY 0.617021 (-7170 4435);
PAINT ORANGE (-7170 4435);
FORCEPROP 1 LAST PACK_TYPE 0402
J 0
(-7135 4350);
DISPLAY 0.617021 (-7135 4350);
PAINT SKYBLUE (-7135 4350);
FORCEPROP 1 LAST TOLERANCE 5%
J 0
(-7130 4550);
DISPLAY 0.617021 (-7130 4550);
PAINT SKYBLUE (-7130 4550);
FORCEPROP 1 LAST WATTAGE 1/16W
J 0
(-7135 4500);
DISPLAY 0.617021 (-7135 4500);
PAINT SKYBLUE (-7135 4500);
FORCEPROP 1 LAST MATERIAL EMPTY
J 0
(-7135 4450);
DISPLAY 0.617021 (-7135 4450);
PAINT RED (-7135 4450);
FORCEPROP 1 LAST PART_NUMBER G21497-005
J 0
(-7135 4400);
DISPLAY 0.617021 (-7135 4400);
PAINT BLUE (-7135 4400);
FORCEPROP 1 LAST VALUE 0.0
J 0
(-7130 4600);
DISPLAY 0.617021 (-7130 4600);
PAINT SKYBLUE (-7130 4600);
FORCEPROP 1 LAST LOCATION R1U56
J 0
(-7130 4650);
DISPLAY 0.617021 (-7130 4650);
PAINT AQUA (-7130 4650);
FORCEPROP 2 LAST CDS_LIB mstr_discrete
J 0
(-7175 4525);
PAINT ORANGE (-7175 4525);
DISPLAY INVISIBLE (-7175 4525);
FORCEPROP 1 LAST PATH I50
J 0
(-7125 4700);
DISPLAY 0.978723 (-7125 4700);
PAINT WHITE (-7125 4700);
DISPLAY INVISIBLE (-7125 4700);
FORCEPROP 2 LAST SEC 1
J 0
(-7125 4750);
DISPLAY 0.680851 (-7125 4750);
PAINT MONO (-7125 4750);
DISPLAY INVISIBLE (-7125 4750);
FORCEPROP 2 LAST SEC_TYPE 0402
J 0
(-7125 4750);
DISPLAY 1.021277 (-7125 4750);
PAINT ORANGE (-7125 4750);
DISPLAY INVISIBLE (-7125 4750);
FORCEADD RES..2
(-7450 4525);
FORCEPROP 1 LASTPIN (-7450 4425) $PN 2
J 0
(-7445 4435);
DISPLAY 0.617021 (-7445 4435);
PAINT ORANGE (-7445 4435);
FORCEPROP 1 LAST PACK_TYPE 0402
J 0
(-7410 4350);
DISPLAY 0.617021 (-7410 4350);
PAINT SKYBLUE (-7410 4350);
FORCEPROP 1 LAST TOLERANCE 5%
J 0
(-7405 4550);
DISPLAY 0.617021 (-7405 4550);
PAINT SKYBLUE (-7405 4550);
FORCEPROP 1 LAST WATTAGE 1/16W
J 0
(-7410 4500);
DISPLAY 0.617021 (-7410 4500);
PAINT SKYBLUE (-7410 4500);
FORCEPROP 1 LAST MATERIAL EMPTY
J 0
(-7410 4450);
DISPLAY 0.617021 (-7410 4450);
PAINT RED (-7410 4450);
FORCEPROP 1 LAST VALUE 0.0
J 0
(-7405 4600);
DISPLAY 0.617021 (-7405 4600);
PAINT SKYBLUE (-7405 4600);
FORCEPROP 1 LASTPIN (-7450 4625) $PN 1
J 0
(-7445 4587);
DISPLAY 0.617021 (-7445 4587);
PAINT ORANGE (-7445 4587);
FORCEPROP 1 LAST LOCATION R2U51
J 0
(-7405 4650);
DISPLAY 0.617021 (-7405 4650);
PAINT AQUA (-7405 4650);
FORCEPROP 1 LAST PART_NUMBER G21497-005
J 0
(-7410 4400);
DISPLAY 0.617021 (-7410 4400);
PAINT BLUE (-7410 4400);
FORCEPROP 2 LAST CDS_LIB mstr_discrete
J 0
(-7450 4525);
PAINT ORANGE (-7450 4525);
DISPLAY INVISIBLE (-7450 4525);
FORCEPROP 2 LAST SEC_TYPE 0402
J 0
(-7400 4750);
DISPLAY 1.021277 (-7400 4750);
PAINT ORANGE (-7400 4750);
DISPLAY INVISIBLE (-7400 4750);
FORCEPROP 2 LAST SEC 1
J 0
(-7400 4750);
DISPLAY 0.680851 (-7400 4750);
PAINT MONO (-7400 4750);
DISPLAY INVISIBLE (-7400 4750);
FORCEPROP 1 LAST PATH I51
J 0
(-7400 4700);
DISPLAY 0.978723 (-7400 4700);
PAINT WHITE (-7400 4700);
DISPLAY INVISIBLE (-7400 4700);
FORCEADD PVCCIO_CPU0..1
(-7925 4950);
FORCEPROP 3 LASTPIN (-7925 4900) SIG_NAME PVCCIO_CPU0\g
J 0
(-7915 4910);
DISPLAY 0.659574 (-7915 4910);
PAINT MONO (-7915 4910);
DISPLAY INVISIBLE (-7915 4910);
FORCEPROP 1 LAST BODY_TYPE PLUMBING
J 0
(-7970 4907);
DISPLAY 0.340426 (-7970 4907);
PAINT GREEN (-7970 4907);
DISPLAY INVISIBLE (-7970 4907);
FORCEPROP 1 LAST VOLTAGE 1.1V
J 0
(-7970 4907);
DISPLAY 0.340426 (-7970 4907);
PAINT SKYBLUE (-7970 4907);
DISPLAY INVISIBLE (-7970 4907);
FORCEPROP 1 LAST HDL_POWER PVCCIO_CPU0
J 1
(-7925 5000);
DISPLAY 0.872340 (-7925 5000);
PAINT GREEN (-7925 5000);
DISPLAY INVISIBLE (-7925 5000);
FORCEPROP 1 LAST PATH I52
J 0
(-7875 4975);
DISPLAY 0.872340 (-7875 4975);
PAINT AQUA (-7875 4975);
DISPLAY INVISIBLE (-7875 4975);
FORCEPROP 2 LAST CDS_LIB mstr_symbols
J 0
(-7925 4950);
PAINT ORANGE (-7925 4950);
DISPLAY INVISIBLE (-7925 4950);
FORCEADD RES..2
(-7875 4650);
FORCEPROP 1 LASTPIN (-7875 4550) $PN 2
J 0
(-7870 4560);
DISPLAY 0.617021 (-7870 4560);
PAINT ORANGE (-7870 4560);
FORCEPROP 1 LAST MATERIAL CHIP
J 0
(-7835 4575);
DISPLAY 0.617021 (-7835 4575);
PAINT SKYBLUE (-7835 4575);
FORCEPROP 1 LAST PACK_TYPE 0402
J 0
(-7835 4475);
DISPLAY 0.617021 (-7835 4475);
PAINT SKYBLUE (-7835 4475);
FORCEPROP 1 LASTPIN (-7875 4750) $PN 1
J 0
(-7870 4712);
DISPLAY 0.617021 (-7870 4712);
PAINT ORANGE (-7870 4712);
FORCEPROP 1 LAST VALUE 150.0
J 0
(-7830 4725);
DISPLAY 0.617021 (-7830 4725);
PAINT SKYBLUE (-7830 4725);
FORCEPROP 1 LAST LOCATION R2U40
J 0
(-7830 4775);
DISPLAY 0.617021 (-7830 4775);
PAINT AQUA (-7830 4775);
FORCEPROP 1 LAST TOLERANCE 1%
J 0
(-7830 4675);
DISPLAY 0.617021 (-7830 4675);
PAINT SKYBLUE (-7830 4675);
FORCEPROP 1 LAST WATTAGE 1/16W
J 0
(-7835 4625);
DISPLAY 0.617021 (-7835 4625);
PAINT SKYBLUE (-7835 4625);
FORCEPROP 1 LAST PART_NUMBER G21796-009
J 0
(-7835 4525);
DISPLAY 0.617021 (-7835 4525);
PAINT BLUE (-7835 4525);
FORCEPROP 2 LAST ROOM PROC_SIDEBAND
J 0
(-7850 4425);
PAINT ORANGE (-7850 4425);
DISPLAY INVISIBLE (-7850 4425);
FORCEPROP 2 LAST BOM_COST PROC_SIDEBAND
J 0
(-7875 4650);
PAINT MONO (-7875 4650);
DISPLAY INVISIBLE (-7875 4650);
FORCEPROP 2 LAST CDS_LIB mstr_discrete
J 0
(-7875 4650);
PAINT MONO (-7875 4650);
DISPLAY INVISIBLE (-7875 4650);
FORCEPROP 2 LAST CDS_LOCATION R2U40
J 0
(-7830 4775);
DISPLAY 0.617021 (-7830 4775);
PAINT AQUA (-7830 4775);
DISPLAY INVISIBLE (-7830 4775);
FORCEPROP 1 LAST PATH I53
J 0
(-7825 4825);
DISPLAY 0.978723 (-7825 4825);
PAINT WHITE (-7825 4825);
DISPLAY INVISIBLE (-7825 4825);
FORCEPROP 2 LAST SEC_TYPE 0402
J 0
(-7825 4875);
DISPLAY 1.021277 (-7825 4875);
PAINT ORANGE (-7825 4875);
DISPLAY INVISIBLE (-7825 4875);
FORCEPROP 2 LAST SEC 1
J 0
(-7825 4875);
DISPLAY 0.680851 (-7825 4875);
PAINT MONO (-7825 4875);
DISPLAY INVISIBLE (-7825 4875);
FORCEADD RES..2
R 2
(-7975 4650);
FORCEPROP 1 LAST PART_NUMBER G21796-009
J 2
(-8040 4525);
DISPLAY 0.617021 (-8040 4525);
PAINT BLUE (-8040 4525);
FORCEPROP 1 LAST MATERIAL CHIP
J 2
(-8015 4575);
DISPLAY 0.617021 (-8015 4575);
PAINT SKYBLUE (-8015 4575);
FORCEPROP 1 LASTPIN (-7975 4550) $PN 2
J 2
(-7980 4560);
DISPLAY 0.617021 (-7980 4560);
PAINT ORANGE (-7980 4560);
FORCEPROP 1 LAST PACK_TYPE 0402
J 2
(-8015 4475);
DISPLAY 0.617021 (-8015 4475);
PAINT SKYBLUE (-8015 4475);
FORCEPROP 1 LAST WATTAGE 1/16W
J 2
(-8015 4625);
DISPLAY 0.617021 (-8015 4625);
PAINT SKYBLUE (-8015 4625);
FORCEPROP 1 LAST VALUE 150.0
J 2
(-8020 4725);
DISPLAY 0.617021 (-8020 4725);
PAINT SKYBLUE (-8020 4725);
FORCEPROP 1 LAST LOCATION R2U41
J 2
(-7995 4775);
DISPLAY 0.617021 (-7995 4775);
PAINT AQUA (-7995 4775);
FORCEPROP 1 LAST TOLERANCE 1%
J 2
(-8020 4675);
DISPLAY 0.617021 (-8020 4675);
PAINT SKYBLUE (-8020 4675);
FORCEPROP 1 LASTPIN (-7975 4750) $PN 1
J 2
(-7980 4712);
DISPLAY 0.617021 (-7980 4712);
PAINT ORANGE (-7980 4712);
FORCEPROP 2 LAST ROOM PROC_SIDEBAND
J 2
(-8000 4425);
PAINT ORANGE (-8000 4425);
DISPLAY INVISIBLE (-8000 4425);
FORCEPROP 2 LAST BOM_COST PROC_SIDEBAND
J 2
(-7975 4650);
PAINT MONO (-7975 4650);
DISPLAY INVISIBLE (-7975 4650);
FORCEPROP 2 LAST CDS_LIB mstr_discrete
J 0
(-7975 4650);
PAINT MONO (-7975 4650);
DISPLAY INVISIBLE (-7975 4650);
FORCEPROP 2 LAST CDS_LOCATION R2U41
J 2
(-7995 4775);
DISPLAY 0.617021 (-7995 4775);
PAINT AQUA (-7995 4775);
DISPLAY INVISIBLE (-7995 4775);
FORCEPROP 1 LAST PATH I54
J 2
(-8025 4825);
DISPLAY 0.978723 (-8025 4825);
PAINT WHITE (-8025 4825);
DISPLAY INVISIBLE (-8025 4825);
FORCEPROP 2 LAST SEC_TYPE 0402
J 0
(-8025 4875);
DISPLAY 1.021277 (-8025 4875);
PAINT ORANGE (-8025 4875);
DISPLAY INVISIBLE (-8025 4875);
FORCEPROP 2 LAST SEC 1
J 0
(-8025 4875);
DISPLAY 0.680851 (-8025 4875);
PAINT MONO (-8025 4875);
DISPLAY INVISIBLE (-8025 4875);
FORCEADD PVCCIO_CPU1..1
(-8375 4950);
FORCEPROP 3 LASTPIN (-8375 4900) SIG_NAME PVCCIO_CPU1\g
J 0
(-8365 4910);
DISPLAY 0.659574 (-8365 4910);
PAINT MONO (-8365 4910);
DISPLAY INVISIBLE (-8365 4910);
FORCEPROP 1 LAST HDL_POWER PVCCIO_CPU1
J 1
(-8375 5000);
DISPLAY 0.872340 (-8375 5000);
PAINT GREEN (-8375 5000);
DISPLAY INVISIBLE (-8375 5000);
FORCEPROP 1 LAST PATH I55
J 0
(-8325 4975);
DISPLAY 0.872340 (-8325 4975);
PAINT AQUA (-8325 4975);
DISPLAY INVISIBLE (-8325 4975);
FORCEPROP 1 LAST BODY_TYPE PLUMBING
J 0
(-8420 4907);
DISPLAY 0.340426 (-8420 4907);
PAINT GREEN (-8420 4907);
DISPLAY INVISIBLE (-8420 4907);
FORCEPROP 2 LAST CDS_LIB mstr_symbols
J 0
(-8375 4950);
PAINT ORANGE (-8375 4950);
DISPLAY INVISIBLE (-8375 4950);
FORCEPROP 1 LAST VOLTAGE 1.1V
J 0
(-8420 4907);
DISPLAY 0.340426 (-8420 4907);
PAINT SKYBLUE (-8420 4907);
DISPLAY INVISIBLE (-8420 4907);
FORCEADD RES..2
(-8325 4650);
FORCEPROP 1 LASTPIN (-8325 4550) $PN 2
J 0
(-8320 4560);
DISPLAY 0.617021 (-8320 4560);
PAINT ORANGE (-8320 4560);
FORCEPROP 1 LASTPIN (-8325 4750) $PN 1
J 0
(-8320 4712);
DISPLAY 0.617021 (-8320 4712);
PAINT ORANGE (-8320 4712);
FORCEPROP 1 LAST TOLERANCE 1%
J 0
(-8280 4675);
DISPLAY 0.617021 (-8280 4675);
PAINT SKYBLUE (-8280 4675);
FORCEPROP 1 LAST WATTAGE 1/16W
J 0
(-8285 4625);
DISPLAY 0.617021 (-8285 4625);
PAINT SKYBLUE (-8285 4625);
FORCEPROP 1 LAST MATERIAL CHIP
J 0
(-8285 4575);
DISPLAY 0.617021 (-8285 4575);
PAINT SKYBLUE (-8285 4575);
FORCEPROP 1 LAST PACK_TYPE 0402
J 0
(-8285 4475);
DISPLAY 0.617021 (-8285 4475);
PAINT SKYBLUE (-8285 4475);
FORCEPROP 1 LAST VALUE 150.0
J 0
(-8280 4725);
DISPLAY 0.617021 (-8280 4725);
PAINT SKYBLUE (-8280 4725);
FORCEPROP 1 LAST LOCATION R1U41
J 0
(-8280 4775);
DISPLAY 0.617021 (-8280 4775);
PAINT AQUA (-8280 4775);
FORCEPROP 2 LAST ROOM PROC_SIDEBAND
J 0
(-8300 4425);
PAINT ORANGE (-8300 4425);
DISPLAY INVISIBLE (-8300 4425);
FORCEPROP 1 LAST PART_NUMBER G21796-009
J 0
(-8285 4525);
DISPLAY 0.617021 (-8285 4525);
PAINT BLUE (-8285 4525);
DISPLAY INVISIBLE (-8285 4525);
FORCEPROP 2 LAST BOM_COST PROC_SIDEBAND
J 0
(-8325 4650);
PAINT MONO (-8325 4650);
DISPLAY INVISIBLE (-8325 4650);
FORCEPROP 2 LAST CDS_LIB mstr_discrete
J 0
(-8325 4650);
PAINT MONO (-8325 4650);
DISPLAY INVISIBLE (-8325 4650);
FORCEPROP 2 LAST CDS_LOCATION R1U41
J 0
(-8280 4775);
DISPLAY 0.617021 (-8280 4775);
PAINT AQUA (-8280 4775);
DISPLAY INVISIBLE (-8280 4775);
FORCEPROP 1 LAST PATH I56
J 0
(-8275 4825);
DISPLAY 0.978723 (-8275 4825);
PAINT WHITE (-8275 4825);
DISPLAY INVISIBLE (-8275 4825);
FORCEPROP 2 LAST SEC 1
J 0
(-8275 4875);
DISPLAY 0.680851 (-8275 4875);
PAINT MONO (-8275 4875);
DISPLAY INVISIBLE (-8275 4875);
FORCEPROP 2 LAST SEC_TYPE 0402
J 0
(-8275 4875);
DISPLAY 1.021277 (-8275 4875);
PAINT ORANGE (-8275 4875);
DISPLAY INVISIBLE (-8275 4875);
FORCEADD RES..2
R 2
(-8425 4650);
FORCEPROP 1 LAST PART_NUMBER G21796-009
J 2
(-8465 4525);
DISPLAY 0.617021 (-8465 4525);
PAINT BLUE (-8465 4525);
FORCEPROP 1 LAST MATERIAL CHIP
J 2
(-8465 4575);
DISPLAY 0.617021 (-8465 4575);
PAINT SKYBLUE (-8465 4575);
FORCEPROP 1 LAST PACK_TYPE 0402
J 2
(-8465 4475);
DISPLAY 0.617021 (-8465 4475);
PAINT SKYBLUE (-8465 4475);
FORCEPROP 1 LASTPIN (-8425 4550) $PN 2
J 2
(-8430 4560);
DISPLAY 0.617021 (-8430 4560);
PAINT ORANGE (-8430 4560);
FORCEPROP 1 LAST WATTAGE 1/16W
J 2
(-8465 4625);
DISPLAY 0.617021 (-8465 4625);
PAINT SKYBLUE (-8465 4625);
FORCEPROP 1 LAST TOLERANCE 1%
J 2
(-8470 4675);
DISPLAY 0.617021 (-8470 4675);
PAINT SKYBLUE (-8470 4675);
FORCEPROP 1 LAST VALUE 150.0
J 2
(-8470 4725);
DISPLAY 0.617021 (-8470 4725);
PAINT SKYBLUE (-8470 4725);
FORCEPROP 1 LAST LOCATION R1U35
J 2
(-8470 4775);
DISPLAY 0.617021 (-8470 4775);
PAINT AQUA (-8470 4775);
FORCEPROP 1 LASTPIN (-8425 4750) $PN 1
J 2
(-8430 4712);
DISPLAY 0.617021 (-8430 4712);
PAINT ORANGE (-8430 4712);
FORCEPROP 2 LAST ROOM PROC_SIDEBAND
J 2
(-8450 4425);
PAINT ORANGE (-8450 4425);
DISPLAY INVISIBLE (-8450 4425);
FORCEPROP 1 LAST PATH I57
J 2
(-8475 4825);
DISPLAY 0.978723 (-8475 4825);
PAINT WHITE (-8475 4825);
DISPLAY INVISIBLE (-8475 4825);
FORCEPROP 2 LAST CDS_LOCATION R1U35
J 2
(-8470 4775);
DISPLAY 0.617021 (-8470 4775);
PAINT AQUA (-8470 4775);
DISPLAY INVISIBLE (-8470 4775);
FORCEPROP 2 LAST SEC 1
J 0
(-8475 4875);
DISPLAY 0.680851 (-8475 4875);
PAINT MONO (-8475 4875);
DISPLAY INVISIBLE (-8475 4875);
FORCEPROP 2 LAST SEC_TYPE 0402
J 0
(-8475 4875);
DISPLAY 1.021277 (-8475 4875);
PAINT ORANGE (-8475 4875);
DISPLAY INVISIBLE (-8475 4875);
FORCEPROP 2 LAST CDS_LIB mstr_discrete
J 0
(-8425 4650);
PAINT MONO (-8425 4650);
DISPLAY INVISIBLE (-8425 4650);
FORCEPROP 2 LAST BOM_COST PROC_SIDEBAND
J 2
(-8425 4650);
PAINT MONO (-8425 4650);
DISPLAY INVISIBLE (-8425 4650);
FORCEADD RES..2
(-7800 3250);
FORCEPROP 1 LASTPIN (-7800 3150) $PN 2
J 0
(-7795 3160);
DISPLAY 0.617021 (-7795 3160);
PAINT ORANGE (-7795 3160);
FORCEPROP 1 LAST TOLERANCE 1%
J 0
(-7755 3275);
DISPLAY 0.617021 (-7755 3275);
PAINT SKYBLUE (-7755 3275);
FORCEPROP 1 LASTPIN (-7800 3350) $PN 1
J 0
(-7795 3312);
DISPLAY 0.617021 (-7795 3312);
PAINT ORANGE (-7795 3312);
FORCEPROP 1 LAST PART_NUMBER G21796-009
J 0
(-7760 3125);
DISPLAY 0.617021 (-7760 3125);
PAINT BLUE (-7760 3125);
FORCEPROP 1 LAST WATTAGE 1/16W
J 0
(-7760 3225);
DISPLAY 0.617021 (-7760 3225);
PAINT SKYBLUE (-7760 3225);
FORCEPROP 1 LAST MATERIAL CHIP
J 0
(-7760 3175);
DISPLAY 0.617021 (-7760 3175);
PAINT SKYBLUE (-7760 3175);
FORCEPROP 1 LAST PACK_TYPE 0402
J 0
(-7760 3075);
DISPLAY 0.617021 (-7760 3075);
PAINT SKYBLUE (-7760 3075);
FORCEPROP 1 LAST VALUE 150.0
J 0
(-7755 3325);
DISPLAY 0.617021 (-7755 3325);
PAINT SKYBLUE (-7755 3325);
FORCEPROP 1 LAST LOCATION R4P17
J 0
(-7755 3375);
DISPLAY 0.617021 (-7755 3375);
PAINT AQUA (-7755 3375);
FORCEPROP 2 LAST ROOM PROC_SIDEBAND
J 0
(-7775 3025);
PAINT ORANGE (-7775 3025);
DISPLAY INVISIBLE (-7775 3025);
FORCEPROP 2 LAST BOM_COST PROC_SIDEBAND
J 0
(-7800 3250);
PAINT MONO (-7800 3250);
DISPLAY INVISIBLE (-7800 3250);
FORCEPROP 2 LAST CDS_LIB mstr_discrete
J 0
(-7800 3250);
PAINT MONO (-7800 3250);
DISPLAY INVISIBLE (-7800 3250);
FORCEPROP 1 LAST PATH I58
J 0
(-7750 3425);
DISPLAY 0.978723 (-7750 3425);
PAINT WHITE (-7750 3425);
DISPLAY INVISIBLE (-7750 3425);
FORCEPROP 2 LAST CDS_LOCATION R4P17
J 0
(-7755 3375);
DISPLAY 0.617021 (-7755 3375);
PAINT AQUA (-7755 3375);
DISPLAY INVISIBLE (-7755 3375);
FORCEPROP 2 LAST SEC 1
J 0
(-7750 3475);
DISPLAY 0.680851 (-7750 3475);
PAINT MONO (-7750 3475);
DISPLAY INVISIBLE (-7750 3475);
FORCEPROP 2 LAST SEC_TYPE 0402
J 0
(-7750 3475);
DISPLAY 1.021277 (-7750 3475);
PAINT ORANGE (-7750 3475);
DISPLAY INVISIBLE (-7750 3475);
FORCEADD RES..2
R 2
(-7900 3250);
FORCEPROP 1 LAST MATERIAL CHIP
J 2
(-7940 3175);
DISPLAY 0.617021 (-7940 3175);
PAINT SKYBLUE (-7940 3175);
FORCEPROP 1 LAST PACK_TYPE 0402
J 2
(-7940 3075);
DISPLAY 0.617021 (-7940 3075);
PAINT SKYBLUE (-7940 3075);
FORCEPROP 1 LAST WATTAGE 1/16W
J 2
(-7940 3225);
DISPLAY 0.617021 (-7940 3225);
PAINT SKYBLUE (-7940 3225);
FORCEPROP 1 LAST TOLERANCE 1%
J 2
(-7945 3275);
DISPLAY 0.617021 (-7945 3275);
PAINT SKYBLUE (-7945 3275);
FORCEPROP 1 LAST VALUE 150.0
J 2
(-7945 3325);
DISPLAY 0.617021 (-7945 3325);
PAINT SKYBLUE (-7945 3325);
FORCEPROP 1 LAST LOCATION R4P20
J 2
(-7895 3400);
DISPLAY 0.617021 (-7895 3400);
PAINT AQUA (-7895 3400);
FORCEPROP 1 LASTPIN (-7900 3150) $PN 2
J 2
(-7905 3160);
DISPLAY 0.617021 (-7905 3160);
PAINT ORANGE (-7905 3160);
FORCEPROP 1 LASTPIN (-7900 3350) $PN 1
J 2
(-7905 3312);
DISPLAY 0.617021 (-7905 3312);
PAINT ORANGE (-7905 3312);
FORCEPROP 2 LAST ROOM PROC_SIDEBAND
J 2
(-7925 3025);
PAINT ORANGE (-7925 3025);
DISPLAY INVISIBLE (-7925 3025);
FORCEPROP 1 LAST PATH I59
J 2
(-7950 3425);
DISPLAY 0.978723 (-7950 3425);
PAINT WHITE (-7950 3425);
DISPLAY INVISIBLE (-7950 3425);
FORCEPROP 2 LAST SEC 1
J 0
(-7950 3475);
DISPLAY 0.680851 (-7950 3475);
PAINT MONO (-7950 3475);
DISPLAY INVISIBLE (-7950 3475);
FORCEPROP 2 LAST SEC_TYPE 0402
J 0
(-7950 3475);
DISPLAY 1.021277 (-7950 3475);
PAINT ORANGE (-7950 3475);
DISPLAY INVISIBLE (-7950 3475);
FORCEPROP 1 LAST PART_NUMBER G21796-009
J 2
(-7915 3125);
DISPLAY 0.617021 (-7915 3125);
PAINT BLUE (-7915 3125);
DISPLAY INVISIBLE (-7915 3125);
FORCEPROP 2 LAST CDS_LIB mstr_discrete
J 0
(-7900 3250);
PAINT MONO (-7900 3250);
DISPLAY INVISIBLE (-7900 3250);
FORCEPROP 2 LAST BOM_COST PROC_SIDEBAND
J 2
(-7900 3250);
PAINT MONO (-7900 3250);
DISPLAY INVISIBLE (-7900 3250);
FORCEPROP 2 LAST CDS_LOCATION R4P20
J 2
(-7895 3400);
DISPLAY 0.617021 (-7895 3400);
PAINT AQUA (-7895 3400);
DISPLAY INVISIBLE (-7895 3400);
FORCEADD RES..1
(-2450 4250);
FORCEPROP 1 LAST VALUE 33.2
J 2
(-2500 4200);
DISPLAY 0.617021 (-2500 4200);
PAINT SKYBLUE (-2500 4200);
FORCEPROP 1 LASTPIN (-2550 4250) $PN 1
J 0
(-2538 4262);
DISPLAY 0.617021 (-2538 4262);
PAINT ORANGE (-2538 4262);
FORCEPROP 1 LAST LOCATION R1U46
J 0
(-2500 4300);
DISPLAY 0.617021 (-2500 4300);
PAINT AQUA (-2500 4300);
FORCEPROP 1 LAST TOLERANCE 1%
J 0
(-2475 4200);
DISPLAY 0.617021 (-2475 4200);
PAINT SKYBLUE (-2475 4200);
FORCEPROP 1 LASTPIN (-2350 4250) $PN 2
J 0
(-2388 4262);
DISPLAY 0.617021 (-2388 4262);
PAINT ORANGE (-2388 4262);
FORCEPROP 1 LAST WATTAGE 1/16W
J 2
(-2250 4200);
DISPLAY 0.617021 (-2250 4200);
PAINT SKYBLUE (-2250 4200);
FORCEPROP 1 LAST PART_NUMBER G21796-074
J 0
(-2225 4200);
DISPLAY 0.617021 (-2225 4200);
PAINT BLUE (-2225 4200);
FORCEPROP 1 LAST MATERIAL CHIP
J 0
(-1900 4200);
DISPLAY 0.617021 (-1900 4200);
PAINT SKYBLUE (-1900 4200);
FORCEPROP 1 LAST PACK_TYPE 0402
J 0
(-2000 4200);
DISPLAY 0.617021 (-2000 4200);
PAINT SKYBLUE (-2000 4200);
FORCEPROP 2 LAST CDS_LOCATION R1U46
J 0
(-2500 4300);
DISPLAY 0.617021 (-2500 4300);
PAINT AQUA (-2500 4300);
DISPLAY INVISIBLE (-2500 4300);
FORCEPROP 2 LAST CDS_LIB mstr_discrete
J 0
(-2450 4250);
PAINT ORANGE (-2450 4250);
DISPLAY INVISIBLE (-2450 4250);
FORCEPROP 2 LAST ROOM PROC_SIDEBAND
J 0
(-2500 4350);
DISPLAY 1.021277 (-2500 4350);
PAINT ORANGE (-2500 4350);
DISPLAY INVISIBLE (-2500 4350);
FORCEPROP 2 LAST SEC_TYPE 0402
J 0
(-2500 4450);
DISPLAY 1.021277 (-2500 4450);
PAINT ORANGE (-2500 4450);
DISPLAY INVISIBLE (-2500 4450);
FORCEPROP 2 LAST BOM_COST PROC_SIDEBAND
J 0
(-2500 4400);
DISPLAY 1.021277 (-2500 4400);
PAINT ORANGE (-2500 4400);
DISPLAY INVISIBLE (-2500 4400);
FORCEPROP 2 LAST SEC 1
J 0
(-2500 4450);
DISPLAY 0.680851 (-2500 4450);
PAINT MONO (-2500 4450);
DISPLAY INVISIBLE (-2500 4450);
FORCEPROP 1 LAST PATH I6
J 0
(-2500 4400);
DISPLAY 0.978723 (-2500 4400);
PAINT WHITE (-2500 4400);
DISPLAY INVISIBLE (-2500 4400);
FORCEADD PVCCIO_CPU0..1
R 6
(-7850 2925);
FORCEPROP 3 LASTPIN (-7850 2975) SIG_NAME PVCCIO_CPU0\g
J 0
(-7840 2985);
DISPLAY 0.659574 (-7840 2985);
PAINT MONO (-7840 2985);
DISPLAY INVISIBLE (-7840 2985);
FORCEPROP 1 LAST HDL_POWER PVCCIO_CPU0
J 1
(-7850 2875);
DISPLAY 0.872340 (-7850 2875);
PAINT GREEN (-7850 2875);
DISPLAY INVISIBLE (-7850 2875);
FORCEPROP 2 LAST CDS_LIB mstr_symbols
J 0
(-7850 2925);
PAINT ORANGE (-7850 2925);
DISPLAY INVISIBLE (-7850 2925);
FORCEPROP 1 LAST VOLTAGE 1.1V
J 0
(-7895 2968);
DISPLAY 0.340426 (-7895 2968);
PAINT SKYBLUE (-7895 2968);
DISPLAY INVISIBLE (-7895 2968);
FORCEPROP 1 LAST BODY_TYPE PLUMBING
J 0
(-7895 2968);
DISPLAY 0.340426 (-7895 2968);
PAINT GREEN (-7895 2968);
DISPLAY INVISIBLE (-7895 2968);
FORCEPROP 1 LAST PATH I60
J 0
(-7800 2900);
DISPLAY 0.872340 (-7800 2900);
PAINT AQUA (-7800 2900);
DISPLAY INVISIBLE (-7800 2900);
FORCEADD RES..2
(-8250 3275);
FORCEPROP 1 LASTPIN (-8250 3175) $PN 2
J 0
(-8245 3185);
DISPLAY 0.617021 (-8245 3185);
PAINT ORANGE (-8245 3185);
FORCEPROP 1 LASTPIN (-8250 3375) $PN 1
J 0
(-8245 3337);
DISPLAY 0.617021 (-8245 3337);
PAINT ORANGE (-8245 3337);
FORCEPROP 1 LAST PART_NUMBER G21796-009
J 0
(-8210 3150);
DISPLAY 0.617021 (-8210 3150);
PAINT BLUE (-8210 3150);
FORCEPROP 1 LAST WATTAGE 1/16W
J 0
(-8210 3250);
DISPLAY 0.617021 (-8210 3250);
PAINT SKYBLUE (-8210 3250);
FORCEPROP 1 LAST MATERIAL CHIP
J 0
(-8210 3200);
DISPLAY 0.617021 (-8210 3200);
PAINT SKYBLUE (-8210 3200);
FORCEPROP 1 LAST PACK_TYPE 0402
J 0
(-8210 3100);
DISPLAY 0.617021 (-8210 3100);
PAINT SKYBLUE (-8210 3100);
FORCEPROP 1 LAST TOLERANCE 1%
J 0
(-8205 3300);
DISPLAY 0.617021 (-8205 3300);
PAINT SKYBLUE (-8205 3300);
FORCEPROP 1 LAST VALUE 150.0
J 0
(-8205 3350);
DISPLAY 0.617021 (-8205 3350);
PAINT SKYBLUE (-8205 3350);
FORCEPROP 1 LAST LOCATION R7P5
J 0
(-8205 3400);
DISPLAY 0.617021 (-8205 3400);
PAINT AQUA (-8205 3400);
FORCEPROP 2 LAST ROOM PROC_SIDEBAND
J 0
(-8225 3050);
PAINT ORANGE (-8225 3050);
DISPLAY INVISIBLE (-8225 3050);
FORCEPROP 2 LAST BOM_COST PROC_SIDEBAND
J 0
(-8250 3275);
PAINT MONO (-8250 3275);
DISPLAY INVISIBLE (-8250 3275);
FORCEPROP 2 LAST CDS_LIB mstr_discrete
J 0
(-8250 3275);
PAINT MONO (-8250 3275);
DISPLAY INVISIBLE (-8250 3275);
FORCEPROP 1 LAST PATH I61
J 0
(-8200 3450);
DISPLAY 0.978723 (-8200 3450);
PAINT WHITE (-8200 3450);
DISPLAY INVISIBLE (-8200 3450);
FORCEPROP 2 LAST CDS_LOCATION R7P5
J 0
(-8205 3400);
DISPLAY 0.617021 (-8205 3400);
PAINT AQUA (-8205 3400);
DISPLAY INVISIBLE (-8205 3400);
FORCEPROP 2 LAST SEC 1
J 0
(-8200 3500);
DISPLAY 0.680851 (-8200 3500);
PAINT MONO (-8200 3500);
DISPLAY INVISIBLE (-8200 3500);
FORCEPROP 2 LAST SEC_TYPE 0402
J 0
(-8200 3500);
DISPLAY 1.021277 (-8200 3500);
PAINT ORANGE (-8200 3500);
DISPLAY INVISIBLE (-8200 3500);
FORCEADD RES..2
R 2
(-8350 3275);
FORCEPROP 1 LAST WATTAGE 1/16W
J 2
(-8390 3250);
DISPLAY 0.617021 (-8390 3250);
PAINT SKYBLUE (-8390 3250);
FORCEPROP 1 LAST MATERIAL CHIP
J 2
(-8390 3200);
DISPLAY 0.617021 (-8390 3200);
PAINT SKYBLUE (-8390 3200);
FORCEPROP 1 LAST PACK_TYPE 0402
J 2
(-8390 3100);
DISPLAY 0.617021 (-8390 3100);
PAINT SKYBLUE (-8390 3100);
FORCEPROP 1 LAST TOLERANCE 1%
J 2
(-8395 3300);
DISPLAY 0.617021 (-8395 3300);
PAINT SKYBLUE (-8395 3300);
FORCEPROP 1 LAST VALUE 150.0
J 2
(-8395 3350);
DISPLAY 0.617021 (-8395 3350);
PAINT SKYBLUE (-8395 3350);
FORCEPROP 1 LAST PART_NUMBER G21796-009
J 2
(-8390 3150);
DISPLAY 0.617021 (-8390 3150);
PAINT BLUE (-8390 3150);
FORCEPROP 1 LAST LOCATION R7P21
J 2
(-8395 3400);
DISPLAY 0.617021 (-8395 3400);
PAINT AQUA (-8395 3400);
FORCEPROP 1 LASTPIN (-8350 3175) $PN 2
J 2
(-8355 3185);
DISPLAY 0.617021 (-8355 3185);
PAINT ORANGE (-8355 3185);
FORCEPROP 1 LASTPIN (-8350 3375) $PN 1
J 2
(-8355 3337);
DISPLAY 0.617021 (-8355 3337);
PAINT ORANGE (-8355 3337);
FORCEPROP 2 LAST ROOM PROC_SIDEBAND
J 2
(-8375 3050);
PAINT ORANGE (-8375 3050);
DISPLAY INVISIBLE (-8375 3050);
FORCEPROP 2 LAST BOM_COST PROC_SIDEBAND
J 2
(-8350 3275);
PAINT MONO (-8350 3275);
DISPLAY INVISIBLE (-8350 3275);
FORCEPROP 2 LAST CDS_LIB mstr_discrete
J 0
(-8350 3275);
PAINT MONO (-8350 3275);
DISPLAY INVISIBLE (-8350 3275);
FORCEPROP 1 LAST PATH I62
J 2
(-8400 3450);
DISPLAY 0.978723 (-8400 3450);
PAINT WHITE (-8400 3450);
DISPLAY INVISIBLE (-8400 3450);
FORCEPROP 2 LAST CDS_LOCATION R7P21
J 2
(-8395 3400);
DISPLAY 0.617021 (-8395 3400);
PAINT AQUA (-8395 3400);
DISPLAY INVISIBLE (-8395 3400);
FORCEPROP 2 LAST SEC 1
J 0
(-8400 3500);
DISPLAY 0.680851 (-8400 3500);
PAINT MONO (-8400 3500);
DISPLAY INVISIBLE (-8400 3500);
FORCEPROP 2 LAST SEC_TYPE 0402
J 0
(-8400 3500);
DISPLAY 1.021277 (-8400 3500);
PAINT ORANGE (-8400 3500);
DISPLAY INVISIBLE (-8400 3500);
FORCEADD PVCCIO_CPU1..1
R 6
(-8300 2925);
FORCEPROP 3 LASTPIN (-8300 2975) SIG_NAME PVCCIO_CPU1\g
J 0
(-8290 2985);
DISPLAY 0.659574 (-8290 2985);
PAINT MONO (-8290 2985);
DISPLAY INVISIBLE (-8290 2985);
FORCEPROP 1 LAST BODY_TYPE PLUMBING
J 0
(-8345 2968);
DISPLAY 0.340426 (-8345 2968);
PAINT GREEN (-8345 2968);
DISPLAY INVISIBLE (-8345 2968);
FORCEPROP 1 LAST VOLTAGE 1.1V
J 0
(-8345 2968);
DISPLAY 0.340426 (-8345 2968);
PAINT SKYBLUE (-8345 2968);
DISPLAY INVISIBLE (-8345 2968);
FORCEPROP 1 LAST PATH I63
J 0
(-8250 2900);
DISPLAY 0.872340 (-8250 2900);
PAINT AQUA (-8250 2900);
DISPLAY INVISIBLE (-8250 2900);
FORCEPROP 1 LAST HDL_POWER PVCCIO_CPU1
J 1
(-8300 2875);
DISPLAY 0.872340 (-8300 2875);
PAINT GREEN (-8300 2875);
DISPLAY INVISIBLE (-8300 2875);
FORCEPROP 2 LAST CDS_LIB mstr_symbols
J 0
(-8300 2925);
PAINT ORANGE (-8300 2925);
DISPLAY INVISIBLE (-8300 2925);
FORCEADD RES..1
(-6950 3900);
FORCEPROP 1 LAST VALUE 0.0
J 2
(-7050 3900);
DISPLAY 0.617021 (-7050 3900);
PAINT SKYBLUE (-7050 3900);
FORCEPROP 1 LASTPIN (-7050 3900) $PN 1
J 0
(-7038 3912);
DISPLAY 0.617021 (-7038 3912);
PAINT ORANGE (-7038 3912);
FORCEPROP 1 LAST LOCATION R1U53
J 0
(-7000 3950);
DISPLAY 0.617021 (-7000 3950);
PAINT AQUA (-7000 3950);
FORCEPROP 1 LAST PART_NUMBER G21497-005
J 0
(-7150 3850);
DISPLAY 0.617021 (-7150 3850);
PAINT BLUE (-7150 3850);
FORCEPROP 1 LASTPIN (-6850 3900) $PN 2
J 0
(-6888 3912);
DISPLAY 0.617021 (-6888 3912);
PAINT ORANGE (-6888 3912);
FORCEPROP 1 LAST MATERIAL CHIP
J 0
(-6875 3850);
DISPLAY 0.617021 (-6875 3850);
PAINT SKYBLUE (-6875 3850);
FORCEPROP 1 LAST WATTAGE 1/16W
J 2
(-6975 3750);
DISPLAY 0.617021 (-6975 3750);
PAINT SKYBLUE (-6975 3750);
DISPLAY INVISIBLE (-6975 3750);
FORCEPROP 1 LAST TOLERANCE 5%
J 0
(-6950 3800);
DISPLAY 0.617021 (-6950 3800);
PAINT SKYBLUE (-6950 3800);
DISPLAY INVISIBLE (-6950 3800);
FORCEPROP 2 LAST CDS_LIB mstr_discrete
J 0
(-6950 3900);
PAINT ORANGE (-6950 3900);
DISPLAY INVISIBLE (-6950 3900);
FORCEPROP 1 LAST PATH I64
J 0
(-7000 4050);
DISPLAY 0.978723 (-7000 4050);
PAINT WHITE (-7000 4050);
DISPLAY INVISIBLE (-7000 4050);
FORCEPROP 1 LAST PACK_TYPE 0402
J 0
(-6700 3750);
DISPLAY 0.617021 (-6700 3750);
PAINT SKYBLUE (-6700 3750);
DISPLAY INVISIBLE (-6700 3750);
FORCEPROP 2 LAST SEC 1
J 0
(-7000 4100);
DISPLAY 0.680851 (-7000 4100);
PAINT MONO (-7000 4100);
DISPLAY INVISIBLE (-7000 4100);
FORCEPROP 2 LAST SEC_TYPE 0402
J 0
(-7000 4100);
DISPLAY 1.021277 (-7000 4100);
PAINT ORANGE (-7000 4100);
DISPLAY INVISIBLE (-7000 4100);
FORCEADD RES..1
(-6950 3750);
FORCEPROP 1 LAST VALUE 0.0
J 2
(-7050 3750);
DISPLAY 0.617021 (-7050 3750);
PAINT SKYBLUE (-7050 3750);
FORCEPROP 1 LASTPIN (-7050 3750) $PN 1
J 0
(-7038 3762);
DISPLAY 0.617021 (-7038 3762);
PAINT ORANGE (-7038 3762);
FORCEPROP 1 LAST PART_NUMBER G21497-005
J 0
(-7150 3700);
DISPLAY 0.617021 (-7150 3700);
PAINT BLUE (-7150 3700);
FORCEPROP 1 LAST LOCATION R1U60
J 0
(-7000 3800);
DISPLAY 0.617021 (-7000 3800);
PAINT AQUA (-7000 3800);
FORCEPROP 1 LASTPIN (-6850 3750) $PN 2
J 0
(-6888 3762);
DISPLAY 0.617021 (-6888 3762);
PAINT ORANGE (-6888 3762);
FORCEPROP 1 LAST MATERIAL CHIP
J 0
(-6875 3700);
DISPLAY 0.617021 (-6875 3700);
PAINT SKYBLUE (-6875 3700);
FORCEPROP 1 LAST TOLERANCE 5%
J 0
(-6950 3650);
DISPLAY 0.617021 (-6950 3650);
PAINT SKYBLUE (-6950 3650);
DISPLAY INVISIBLE (-6950 3650);
FORCEPROP 1 LAST WATTAGE 1/16W
J 2
(-6975 3600);
DISPLAY 0.617021 (-6975 3600);
PAINT SKYBLUE (-6975 3600);
DISPLAY INVISIBLE (-6975 3600);
FORCEPROP 2 LAST CDS_LIB mstr_discrete
J 0
(-6950 3750);
PAINT ORANGE (-6950 3750);
DISPLAY INVISIBLE (-6950 3750);
FORCEPROP 1 LAST PATH I65
J 0
(-7000 3900);
DISPLAY 0.978723 (-7000 3900);
PAINT WHITE (-7000 3900);
DISPLAY INVISIBLE (-7000 3900);
FORCEPROP 2 LAST SEC_TYPE 0402
J 0
(-7000 3950);
DISPLAY 1.021277 (-7000 3950);
PAINT ORANGE (-7000 3950);
DISPLAY INVISIBLE (-7000 3950);
FORCEPROP 2 LAST SEC 1
J 0
(-7000 3950);
DISPLAY 0.680851 (-7000 3950);
PAINT MONO (-7000 3950);
DISPLAY INVISIBLE (-7000 3950);
FORCEPROP 1 LAST PACK_TYPE 0402
J 0
(-6700 3600);
DISPLAY 0.617021 (-6700 3600);
PAINT SKYBLUE (-6700 3600);
DISPLAY INVISIBLE (-6700 3600);
FORCEADD RES..2
(-2850 4600);
FORCEPROP 1 LASTPIN (-2850 4500) $PN 2
J 0
(-2845 4510);
DISPLAY 0.617021 (-2845 4510);
PAINT ORANGE (-2845 4510);
FORCEPROP 1 LAST PACK_TYPE 0402
J 0
(-2810 4425);
DISPLAY 0.617021 (-2810 4425);
PAINT SKYBLUE (-2810 4425);
FORCEPROP 1 LAST WATTAGE 1/16W
J 0
(-2810 4575);
DISPLAY 0.617021 (-2810 4575);
PAINT SKYBLUE (-2810 4575);
FORCEPROP 1 LAST MATERIAL EMPTY
J 0
(-2810 4525);
DISPLAY 0.617021 (-2810 4525);
PAINT RED (-2810 4525);
FORCEPROP 1 LASTPIN (-2850 4700) $PN 1
J 0
(-2845 4662);
DISPLAY 0.617021 (-2845 4662);
PAINT ORANGE (-2845 4662);
FORCEPROP 1 LAST TOLERANCE 5%
J 0
(-2805 4625);
DISPLAY 0.617021 (-2805 4625);
PAINT SKYBLUE (-2805 4625);
FORCEPROP 1 LAST VALUE 0.0
J 0
(-2805 4675);
DISPLAY 0.617021 (-2805 4675);
PAINT SKYBLUE (-2805 4675);
FORCEPROP 1 LAST LOCATION R2U49
J 0
(-2805 4725);
DISPLAY 0.617021 (-2805 4725);
PAINT AQUA (-2805 4725);
FORCEPROP 1 LAST PART_NUMBER G21497-005
J 0
(-2810 4475);
DISPLAY 0.617021 (-2810 4475);
PAINT BLUE (-2810 4475);
FORCEPROP 2 LAST CDS_LIB mstr_discrete
J 0
(-2850 4600);
PAINT ORANGE (-2850 4600);
DISPLAY INVISIBLE (-2850 4600);
FORCEPROP 1 LAST PATH I66
J 0
(-2800 4775);
DISPLAY 0.978723 (-2800 4775);
PAINT WHITE (-2800 4775);
DISPLAY INVISIBLE (-2800 4775);
FORCEPROP 2 LAST SEC 1
J 0
(-2800 4825);
DISPLAY 0.680851 (-2800 4825);
PAINT MONO (-2800 4825);
DISPLAY INVISIBLE (-2800 4825);
FORCEPROP 2 LAST SEC_TYPE 0402
J 0
(-2800 4825);
DISPLAY 1.021277 (-2800 4825);
PAINT ORANGE (-2800 4825);
DISPLAY INVISIBLE (-2800 4825);
FORCEADD RES..2
(-7175 3500);
FORCEPROP 1 LASTPIN (-7175 3600) $PN 1
J 0
(-7170 3562);
DISPLAY 0.617021 (-7170 3562);
PAINT ORANGE (-7170 3562);
FORCEPROP 1 LASTPIN (-7175 3400) $PN 2
J 0
(-7170 3410);
DISPLAY 0.617021 (-7170 3410);
PAINT ORANGE (-7170 3410);
FORCEPROP 1 LAST PACK_TYPE 0402
J 0
(-7135 3325);
DISPLAY 0.617021 (-7135 3325);
PAINT SKYBLUE (-7135 3325);
FORCEPROP 1 LAST TOLERANCE 5%
J 0
(-7130 3525);
DISPLAY 0.617021 (-7130 3525);
PAINT SKYBLUE (-7130 3525);
FORCEPROP 1 LAST WATTAGE 1/16W
J 0
(-7135 3475);
DISPLAY 0.617021 (-7135 3475);
PAINT SKYBLUE (-7135 3475);
FORCEPROP 1 LAST MATERIAL EMPTY
J 0
(-7135 3425);
DISPLAY 0.617021 (-7135 3425);
PAINT RED (-7135 3425);
FORCEPROP 1 LAST PART_NUMBER G21497-005
J 0
(-7135 3375);
DISPLAY 0.617021 (-7135 3375);
PAINT BLUE (-7135 3375);
FORCEPROP 1 LAST VALUE 0.0
J 0
(-7130 3575);
DISPLAY 0.617021 (-7130 3575);
PAINT SKYBLUE (-7130 3575);
FORCEPROP 1 LAST LOCATION R1U55
J 0
(-7130 3625);
DISPLAY 0.617021 (-7130 3625);
PAINT AQUA (-7130 3625);
FORCEPROP 2 LAST CDS_LIB mstr_discrete
J 0
(-7175 3500);
PAINT ORANGE (-7175 3500);
DISPLAY INVISIBLE (-7175 3500);
FORCEPROP 2 LAST SEC_TYPE 0402
J 0
(-7125 3725);
DISPLAY 1.021277 (-7125 3725);
PAINT ORANGE (-7125 3725);
DISPLAY INVISIBLE (-7125 3725);
FORCEPROP 2 LAST SEC 1
J 0
(-7125 3725);
DISPLAY 0.680851 (-7125 3725);
PAINT MONO (-7125 3725);
DISPLAY INVISIBLE (-7125 3725);
FORCEPROP 1 LAST PATH I67
J 0
(-7125 3675);
DISPLAY 0.978723 (-7125 3675);
PAINT WHITE (-7125 3675);
DISPLAY INVISIBLE (-7125 3675);
FORCEADD RES..2
(-7450 3500);
FORCEPROP 1 LASTPIN (-7450 3400) $PN 2
J 0
(-7445 3410);
DISPLAY 0.617021 (-7445 3410);
PAINT ORANGE (-7445 3410);
FORCEPROP 1 LAST PACK_TYPE 0402
J 0
(-7410 3325);
DISPLAY 0.617021 (-7410 3325);
PAINT SKYBLUE (-7410 3325);
FORCEPROP 1 LAST TOLERANCE 5%
J 0
(-7405 3525);
DISPLAY 0.617021 (-7405 3525);
PAINT SKYBLUE (-7405 3525);
FORCEPROP 1 LAST WATTAGE 1/16W
J 0
(-7410 3475);
DISPLAY 0.617021 (-7410 3475);
PAINT SKYBLUE (-7410 3475);
FORCEPROP 1 LAST MATERIAL EMPTY
J 0
(-7410 3425);
DISPLAY 0.617021 (-7410 3425);
PAINT RED (-7410 3425);
FORCEPROP 1 LAST VALUE 0.0
J 0
(-7405 3575);
DISPLAY 0.617021 (-7405 3575);
PAINT SKYBLUE (-7405 3575);
FORCEPROP 1 LASTPIN (-7450 3600) $PN 1
J 0
(-7445 3562);
DISPLAY 0.617021 (-7445 3562);
PAINT ORANGE (-7445 3562);
FORCEPROP 1 LAST LOCATION R1U62
J 0
(-7405 3625);
DISPLAY 0.617021 (-7405 3625);
PAINT AQUA (-7405 3625);
FORCEPROP 1 LAST PART_NUMBER G21497-005
J 0
(-7410 3375);
DISPLAY 0.617021 (-7410 3375);
PAINT BLUE (-7410 3375);
FORCEPROP 2 LAST CDS_LIB mstr_discrete
J 0
(-7450 3500);
PAINT ORANGE (-7450 3500);
DISPLAY INVISIBLE (-7450 3500);
FORCEPROP 1 LAST PATH I68
J 0
(-7400 3675);
DISPLAY 0.978723 (-7400 3675);
PAINT WHITE (-7400 3675);
DISPLAY INVISIBLE (-7400 3675);
FORCEPROP 2 LAST SEC 1
J 0
(-7400 3725);
DISPLAY 0.680851 (-7400 3725);
PAINT MONO (-7400 3725);
DISPLAY INVISIBLE (-7400 3725);
FORCEPROP 2 LAST SEC_TYPE 0402
J 0
(-7400 3725);
DISPLAY 1.021277 (-7400 3725);
PAINT ORANGE (-7400 3725);
DISPLAY INVISIBLE (-7400 3725);
FORCEADD RES..2
(-3175 3425);
FORCEPROP 1 LASTPIN (-3175 3325) $PN 2
J 0
(-3170 3335);
DISPLAY 0.617021 (-3170 3335);
PAINT ORANGE (-3170 3335);
FORCEPROP 1 LASTPIN (-3175 3525) $PN 1
J 0
(-3170 3487);
DISPLAY 0.617021 (-3170 3487);
PAINT ORANGE (-3170 3487);
FORCEPROP 1 LAST WATTAGE 1/16W
J 0
(-3135 3400);
DISPLAY 0.617021 (-3135 3400);
PAINT SKYBLUE (-3135 3400);
FORCEPROP 1 LAST PACK_TYPE 0402
J 0
(-3135 3250);
DISPLAY 0.617021 (-3135 3250);
PAINT SKYBLUE (-3135 3250);
FORCEPROP 1 LAST TOLERANCE 5%
J 0
(-3130 3450);
DISPLAY 0.617021 (-3130 3450);
PAINT SKYBLUE (-3130 3450);
FORCEPROP 1 LAST VALUE 0.0
J 0
(-3130 3500);
DISPLAY 0.617021 (-3130 3500);
PAINT SKYBLUE (-3130 3500);
FORCEPROP 1 LAST PART_NUMBER G21497-005
J 0
(-3135 3300);
DISPLAY 0.617021 (-3135 3300);
PAINT BLUE (-3135 3300);
FORCEPROP 1 LAST LOCATION R1U57
J 0
(-3130 3550);
DISPLAY 0.617021 (-3130 3550);
PAINT AQUA (-3130 3550);
FORCEPROP 1 LAST MATERIAL EMPTY
J 0
(-3135 3350);
DISPLAY 0.617021 (-3135 3350);
PAINT RED (-3135 3350);
FORCEPROP 2 LAST CDS_LIB mstr_discrete
J 0
(-3175 3425);
PAINT ORANGE (-3175 3425);
DISPLAY INVISIBLE (-3175 3425);
FORCEPROP 2 LAST SEC_TYPE 0402
J 0
(-3125 3650);
DISPLAY 1.021277 (-3125 3650);
PAINT ORANGE (-3125 3650);
DISPLAY INVISIBLE (-3125 3650);
FORCEPROP 2 LAST SEC 1
J 0
(-3125 3650);
DISPLAY 0.680851 (-3125 3650);
PAINT MONO (-3125 3650);
DISPLAY INVISIBLE (-3125 3650);
FORCEPROP 1 LAST PATH I69
J 0
(-3125 3600);
DISPLAY 0.978723 (-3125 3600);
PAINT WHITE (-3125 3600);
DISPLAY INVISIBLE (-3125 3600);
FORCEADD RES..2
(-2875 3425);
FORCEPROP 1 LASTPIN (-2875 3325) $PN 2
J 0
(-2870 3335);
DISPLAY 0.617021 (-2870 3335);
PAINT ORANGE (-2870 3335);
FORCEPROP 1 LASTPIN (-2875 3525) $PN 1
J 0
(-2870 3487);
DISPLAY 0.617021 (-2870 3487);
PAINT ORANGE (-2870 3487);
FORCEPROP 1 LAST WATTAGE 1/16W
J 0
(-2835 3400);
DISPLAY 0.617021 (-2835 3400);
PAINT SKYBLUE (-2835 3400);
FORCEPROP 1 LAST PACK_TYPE 0402
J 0
(-2835 3250);
DISPLAY 0.617021 (-2835 3250);
PAINT SKYBLUE (-2835 3250);
FORCEPROP 1 LAST TOLERANCE 5%
J 0
(-2830 3450);
DISPLAY 0.617021 (-2830 3450);
PAINT SKYBLUE (-2830 3450);
FORCEPROP 1 LAST VALUE 0.0
J 0
(-2830 3500);
DISPLAY 0.617021 (-2830 3500);
PAINT SKYBLUE (-2830 3500);
FORCEPROP 1 LAST LOCATION R1U61
J 0
(-2830 3550);
DISPLAY 0.617021 (-2830 3550);
PAINT AQUA (-2830 3550);
FORCEPROP 1 LAST MATERIAL EMPTY
J 0
(-2835 3350);
DISPLAY 0.617021 (-2835 3350);
PAINT RED (-2835 3350);
FORCEPROP 1 LAST PART_NUMBER G21497-005
J 0
(-2835 3300);
DISPLAY 0.617021 (-2835 3300);
PAINT BLUE (-2835 3300);
FORCEPROP 2 LAST CDS_LIB mstr_discrete
J 0
(-2875 3425);
PAINT ORANGE (-2875 3425);
DISPLAY INVISIBLE (-2875 3425);
FORCEPROP 1 LAST PATH I70
J 0
(-2825 3600);
DISPLAY 0.978723 (-2825 3600);
PAINT WHITE (-2825 3600);
DISPLAY INVISIBLE (-2825 3600);
FORCEPROP 2 LAST SEC 1
J 0
(-2825 3650);
DISPLAY 0.680851 (-2825 3650);
PAINT MONO (-2825 3650);
DISPLAY INVISIBLE (-2825 3650);
FORCEPROP 2 LAST SEC_TYPE 0402
J 0
(-2825 3650);
DISPLAY 1.021277 (-2825 3650);
PAINT ORANGE (-2825 3650);
DISPLAY INVISIBLE (-2825 3650);
FORCEADD RES..1
(-3375 3725);
FORCEPROP 1 LAST VALUE 0.0
J 2
(-3475 3725);
DISPLAY 0.617021 (-3475 3725);
PAINT SKYBLUE (-3475 3725);
FORCEPROP 1 LAST MATERIAL CHIP
J 0
(-3500 3675);
DISPLAY 0.617021 (-3500 3675);
PAINT SKYBLUE (-3500 3675);
FORCEPROP 1 LASTPIN (-3475 3725) $PN 1
J 0
(-3463 3737);
DISPLAY 0.617021 (-3463 3737);
PAINT ORANGE (-3463 3737);
FORCEPROP 1 LAST PART_NUMBER G21497-005
J 0
(-3400 3675);
DISPLAY 0.617021 (-3400 3675);
PAINT BLUE (-3400 3675);
FORCEPROP 1 LAST LOCATION R9G28
J 0
(-3425 3775);
DISPLAY 0.617021 (-3425 3775);
PAINT AQUA (-3425 3775);
FORCEPROP 1 LASTPIN (-3275 3725) $PN 2
J 0
(-3313 3737);
DISPLAY 0.617021 (-3313 3737);
PAINT ORANGE (-3313 3737);
FORCEPROP 1 LAST WATTAGE 1/16W
J 2
(-3400 3575);
DISPLAY 0.617021 (-3400 3575);
PAINT SKYBLUE (-3400 3575);
DISPLAY INVISIBLE (-3400 3575);
FORCEPROP 1 LAST PACK_TYPE 0402
J 0
(-3125 3575);
DISPLAY 0.617021 (-3125 3575);
PAINT SKYBLUE (-3125 3575);
DISPLAY INVISIBLE (-3125 3575);
FORCEPROP 1 LAST TOLERANCE 5%
J 0
(-3375 3625);
DISPLAY 0.617021 (-3375 3625);
PAINT SKYBLUE (-3375 3625);
DISPLAY INVISIBLE (-3375 3625);
FORCEPROP 2 LAST CDS_LIB mstr_discrete
J 0
(-3375 3725);
PAINT ORANGE (-3375 3725);
DISPLAY INVISIBLE (-3375 3725);
FORCEPROP 1 LAST PATH I71
J 0
(-3425 3875);
DISPLAY 0.978723 (-3425 3875);
PAINT WHITE (-3425 3875);
DISPLAY INVISIBLE (-3425 3875);
FORCEPROP 2 LAST SEC 1
J 0
(-3425 3925);
DISPLAY 0.680851 (-3425 3925);
PAINT MONO (-3425 3925);
DISPLAY INVISIBLE (-3425 3925);
FORCEPROP 2 LAST SEC_TYPE 0402
J 0
(-3425 3925);
DISPLAY 1.021277 (-3425 3925);
PAINT ORANGE (-3425 3925);
DISPLAY INVISIBLE (-3425 3925);
FORCEADD RES..1
(-3375 3900);
FORCEPROP 1 LAST VALUE 0.0
J 2
(-3475 3900);
DISPLAY 0.617021 (-3475 3900);
PAINT SKYBLUE (-3475 3900);
FORCEPROP 1 LASTPIN (-3475 3900) $PN 1
J 0
(-3463 3912);
DISPLAY 0.617021 (-3463 3912);
PAINT ORANGE (-3463 3912);
FORCEPROP 1 LAST MATERIAL CHIP
J 0
(-3500 3850);
DISPLAY 0.617021 (-3500 3850);
PAINT SKYBLUE (-3500 3850);
FORCEPROP 1 LAST PART_NUMBER G21497-005
J 0
(-3400 3850);
DISPLAY 0.617021 (-3400 3850);
PAINT BLUE (-3400 3850);
FORCEPROP 1 LAST LOCATION R9G32
J 0
(-3425 3950);
DISPLAY 0.617021 (-3425 3950);
PAINT AQUA (-3425 3950);
FORCEPROP 1 LASTPIN (-3275 3900) $PN 2
J 0
(-3313 3912);
DISPLAY 0.617021 (-3313 3912);
PAINT ORANGE (-3313 3912);
FORCEPROP 1 LAST TOLERANCE 5%
J 0
(-3375 3800);
DISPLAY 0.617021 (-3375 3800);
PAINT SKYBLUE (-3375 3800);
DISPLAY INVISIBLE (-3375 3800);
FORCEPROP 1 LAST WATTAGE 1/16W
J 2
(-3400 3750);
DISPLAY 0.617021 (-3400 3750);
PAINT SKYBLUE (-3400 3750);
DISPLAY INVISIBLE (-3400 3750);
FORCEPROP 2 LAST CDS_LIB mstr_discrete
J 0
(-3375 3900);
PAINT ORANGE (-3375 3900);
DISPLAY INVISIBLE (-3375 3900);
FORCEPROP 1 LAST PATH I72
J 0
(-3425 4050);
DISPLAY 0.978723 (-3425 4050);
PAINT WHITE (-3425 4050);
DISPLAY INVISIBLE (-3425 4050);
FORCEPROP 1 LAST PACK_TYPE 0402
J 0
(-3125 3750);
DISPLAY 0.617021 (-3125 3750);
PAINT SKYBLUE (-3125 3750);
DISPLAY INVISIBLE (-3125 3750);
FORCEPROP 2 LAST SEC_TYPE 0402
J 0
(-3425 4100);
DISPLAY 1.021277 (-3425 4100);
PAINT ORANGE (-3425 4100);
DISPLAY INVISIBLE (-3425 4100);
FORCEPROP 2 LAST SEC 1
J 0
(-3425 4100);
DISPLAY 0.680851 (-3425 4100);
PAINT MONO (-3425 4100);
DISPLAY INVISIBLE (-3425 4100);
FORCEADD RES..1
(-3375 4075);
FORCEPROP 1 LAST MATERIAL CHIP
J 0
(-3500 4025);
DISPLAY 0.617021 (-3500 4025);
PAINT SKYBLUE (-3500 4025);
FORCEPROP 1 LAST PART_NUMBER G21497-005
J 0
(-3400 4025);
DISPLAY 0.617021 (-3400 4025);
PAINT BLUE (-3400 4025);
FORCEPROP 1 LASTPIN (-3475 4075) $PN 1
J 0
(-3463 4087);
DISPLAY 0.617021 (-3463 4087);
PAINT ORANGE (-3463 4087);
FORCEPROP 1 LASTPIN (-3275 4075) $PN 2
J 0
(-3313 4087);
DISPLAY 0.617021 (-3313 4087);
PAINT ORANGE (-3313 4087);
FORCEPROP 1 LAST VALUE 0.0
J 2
(-3475 4075);
DISPLAY 0.617021 (-3475 4075);
PAINT SKYBLUE (-3475 4075);
FORCEPROP 1 LAST LOCATION R9G33
J 0
(-3425 4125);
DISPLAY 0.617021 (-3425 4125);
PAINT AQUA (-3425 4125);
FORCEPROP 1 LAST WATTAGE 1/16W
J 2
(-3400 3925);
DISPLAY 0.617021 (-3400 3925);
PAINT SKYBLUE (-3400 3925);
DISPLAY INVISIBLE (-3400 3925);
FORCEPROP 1 LAST TOLERANCE 5%
J 0
(-3375 3975);
DISPLAY 0.617021 (-3375 3975);
PAINT SKYBLUE (-3375 3975);
DISPLAY INVISIBLE (-3375 3975);
FORCEPROP 1 LAST PACK_TYPE 0402
J 0
(-3125 3925);
DISPLAY 0.617021 (-3125 3925);
PAINT SKYBLUE (-3125 3925);
DISPLAY INVISIBLE (-3125 3925);
FORCEPROP 2 LAST CDS_LIB mstr_discrete
J 0
(-3375 4075);
PAINT ORANGE (-3375 4075);
DISPLAY INVISIBLE (-3375 4075);
FORCEPROP 2 LAST SEC_TYPE 0402
J 0
(-3425 4275);
DISPLAY 1.021277 (-3425 4275);
PAINT ORANGE (-3425 4275);
DISPLAY INVISIBLE (-3425 4275);
FORCEPROP 2 LAST SEC 1
J 0
(-3425 4275);
DISPLAY 0.680851 (-3425 4275);
PAINT MONO (-3425 4275);
DISPLAY INVISIBLE (-3425 4275);
FORCEPROP 1 LAST PATH I73
J 0
(-3425 4225);
DISPLAY 0.978723 (-3425 4225);
PAINT WHITE (-3425 4225);
DISPLAY INVISIBLE (-3425 4225);
FORCEADD RES..1
(-3375 4250);
FORCEPROP 1 LAST VALUE 0.0
J 2
(-3475 4250);
DISPLAY 0.617021 (-3475 4250);
PAINT SKYBLUE (-3475 4250);
FORCEPROP 1 LAST MATERIAL CHIP
J 0
(-3500 4200);
DISPLAY 0.617021 (-3500 4200);
PAINT SKYBLUE (-3500 4200);
FORCEPROP 1 LASTPIN (-3475 4250) $PN 1
J 0
(-3463 4262);
DISPLAY 0.617021 (-3463 4262);
PAINT ORANGE (-3463 4262);
FORCEPROP 1 LAST PART_NUMBER G21497-005
J 0
(-3400 4200);
DISPLAY 0.617021 (-3400 4200);
PAINT BLUE (-3400 4200);
FORCEPROP 1 LAST LOCATION R1U59
J 0
(-3425 4300);
DISPLAY 0.617021 (-3425 4300);
PAINT AQUA (-3425 4300);
FORCEPROP 1 LASTPIN (-3275 4250) $PN 2
J 0
(-3313 4262);
DISPLAY 0.617021 (-3313 4262);
PAINT ORANGE (-3313 4262);
FORCEPROP 1 LAST TOLERANCE 5%
J 0
(-3375 4150);
DISPLAY 0.617021 (-3375 4150);
PAINT SKYBLUE (-3375 4150);
DISPLAY INVISIBLE (-3375 4150);
FORCEPROP 1 LAST WATTAGE 1/16W
J 2
(-3400 4100);
DISPLAY 0.617021 (-3400 4100);
PAINT SKYBLUE (-3400 4100);
DISPLAY INVISIBLE (-3400 4100);
FORCEPROP 2 LAST CDS_LIB mstr_discrete
J 0
(-3375 4250);
PAINT ORANGE (-3375 4250);
DISPLAY INVISIBLE (-3375 4250);
FORCEPROP 2 LAST SEC_TYPE 0402
J 0
(-3425 4450);
DISPLAY 1.021277 (-3425 4450);
PAINT ORANGE (-3425 4450);
DISPLAY INVISIBLE (-3425 4450);
FORCEPROP 2 LAST SEC 1
J 0
(-3425 4450);
DISPLAY 0.680851 (-3425 4450);
PAINT MONO (-3425 4450);
DISPLAY INVISIBLE (-3425 4450);
FORCEPROP 1 LAST PATH I74
J 0
(-3425 4400);
DISPLAY 0.978723 (-3425 4400);
PAINT WHITE (-3425 4400);
DISPLAY INVISIBLE (-3425 4400);
FORCEPROP 1 LAST PACK_TYPE 0402
J 0
(-3125 4100);
DISPLAY 0.617021 (-3125 4100);
PAINT SKYBLUE (-3125 4100);
DISPLAY INVISIBLE (-3125 4100);
FORCEADD OFFPAGE..1
(-7825 2475);
FORCEPROP 2 LAST $XR0 152 
J 0
(-8077 2475);
DISPLAY 0.638298 (-8077 2475);
PAINT MONO (-8077 2475);
FORCEPROP 1 LAST COMMENT_BODY TRUE
J 0
(-7700 2375);
DISPLAY 0.872340 (-7700 2375);
PAINT GREEN (-7700 2375);
DISPLAY INVISIBLE (-7700 2375);
FORCEPROP 2 LAST CDS_LIB mstr_standard
J 0
(-7825 2475);
PAINT ORANGE (-7825 2475);
DISPLAY INVISIBLE (-7825 2475);
FORCEPROP 2 LAST PATH I75
J 0
(-7500 2525);
DISPLAY 1.021277 (-7500 2525);
PAINT ORANGE (-7500 2525);
DISPLAY INVISIBLE (-7500 2525);
FORCEPROP 1 LAST OFFPAGE TRUE
J 0
(-7500 2350);
DISPLAY 0.872340 (-7500 2350);
PAINT GREEN (-7500 2350);
DISPLAY INVISIBLE (-7500 2350);
FORCEADD OFFPAGE..1
(-7800 2025);
FORCEPROP 2 LAST $XR0 152 
J 0
(-8052 2025);
DISPLAY 0.638298 (-8052 2025);
PAINT MONO (-8052 2025);
FORCEPROP 1 LAST COMMENT_BODY TRUE
J 0
(-7675 1925);
DISPLAY 0.872340 (-7675 1925);
PAINT GREEN (-7675 1925);
DISPLAY INVISIBLE (-7675 1925);
FORCEPROP 1 LAST OFFPAGE TRUE
J 0
(-7475 1900);
DISPLAY 0.872340 (-7475 1900);
PAINT GREEN (-7475 1900);
DISPLAY INVISIBLE (-7475 1900);
FORCEPROP 2 LAST CDS_LIB mstr_standard
J 0
(-7800 2025);
PAINT ORANGE (-7800 2025);
DISPLAY INVISIBLE (-7800 2025);
FORCEPROP 2 LAST PATH I76
J 0
(-7475 2075);
DISPLAY 1.021277 (-7475 2075);
PAINT ORANGE (-7475 2075);
DISPLAY INVISIBLE (-7475 2075);
FORCEADD OFFPAGE..1
(-7800 1600);
FORCEPROP 2 LAST $XR0 152 
J 0
(-8052 1600);
DISPLAY 0.638298 (-8052 1600);
PAINT MONO (-8052 1600);
FORCEPROP 2 LAST CDS_LIB mstr_standard
J 0
(-7800 1600);
PAINT ORANGE (-7800 1600);
DISPLAY INVISIBLE (-7800 1600);
FORCEPROP 2 LAST PATH I77
J 0
(-7475 1650);
DISPLAY 1.021277 (-7475 1650);
PAINT ORANGE (-7475 1650);
DISPLAY INVISIBLE (-7475 1650);
FORCEPROP 1 LAST COMMENT_BODY TRUE
J 0
(-7675 1500);
DISPLAY 0.872340 (-7675 1500);
PAINT GREEN (-7675 1500);
DISPLAY INVISIBLE (-7675 1500);
FORCEPROP 1 LAST OFFPAGE TRUE
J 0
(-7475 1475);
DISPLAY 0.872340 (-7475 1475);
PAINT GREEN (-7475 1475);
DISPLAY INVISIBLE (-7475 1475);
FORCEADD OFFPAGE..1
(-7825 1175);
FORCEPROP 2 LAST $XR0 152 
J 0
(-8077 1175);
DISPLAY 0.638298 (-8077 1175);
PAINT MONO (-8077 1175);
FORCEPROP 1 LAST COMMENT_BODY TRUE
J 0
(-7700 1075);
DISPLAY 0.872340 (-7700 1075);
PAINT GREEN (-7700 1075);
DISPLAY INVISIBLE (-7700 1075);
FORCEPROP 2 LAST CDS_LIB mstr_standard
J 0
(-7825 1175);
PAINT ORANGE (-7825 1175);
DISPLAY INVISIBLE (-7825 1175);
FORCEPROP 2 LAST PATH I78
J 0
(-7500 1225);
DISPLAY 1.021277 (-7500 1225);
PAINT ORANGE (-7500 1225);
DISPLAY INVISIBLE (-7500 1225);
FORCEPROP 1 LAST OFFPAGE TRUE
J 0
(-7500 1050);
DISPLAY 0.872340 (-7500 1050);
PAINT GREEN (-7500 1050);
DISPLAY INVISIBLE (-7500 1050);
FORCEADD RES..1
(-6700 2475);
FORCEPROP 1 LAST WATTAGE 1/16W
J 2
(-6800 2425);
DISPLAY 0.617021 (-6800 2425);
PAINT SKYBLUE (-6800 2425);
FORCEPROP 1 LAST VALUE 0.0
J 2
(-6800 2475);
DISPLAY 0.617021 (-6800 2475);
PAINT SKYBLUE (-6800 2475);
FORCEPROP 1 LASTPIN (-6800 2475) $PN 1
J 0
(-6788 2487);
DISPLAY 0.617021 (-6788 2487);
PAINT ORANGE (-6788 2487);
FORCEPROP 1 LAST TOLERANCE 5%
J 0
(-6775 2425);
DISPLAY 0.617021 (-6775 2425);
PAINT SKYBLUE (-6775 2425);
FORCEPROP 1 LAST MATERIAL CHIP
J 0
(-6700 2425);
DISPLAY 0.617021 (-6700 2425);
PAINT SKYBLUE (-6700 2425);
FORCEPROP 1 LAST PART_NUMBER G21497-005
J 0
(-6850 2575);
DISPLAY 0.617021 (-6850 2575);
PAINT BLUE (-6850 2575);
FORCEPROP 1 LAST LOCATION R2U47
J 0
(-6750 2525);
DISPLAY 0.617021 (-6750 2525);
PAINT AQUA (-6750 2525);
FORCEPROP 1 LASTPIN (-6600 2475) $PN 2
J 0
(-6638 2487);
DISPLAY 0.617021 (-6638 2487);
PAINT ORANGE (-6638 2487);
FORCEPROP 1 LAST PACK_TYPE 0402
J 0
(-6600 2425);
DISPLAY 0.617021 (-6600 2425);
PAINT SKYBLUE (-6600 2425);
FORCEPROP 2 LAST CDS_LIB mstr_discrete
J 0
(-6700 2475);
PAINT ORANGE (-6700 2475);
DISPLAY INVISIBLE (-6700 2475);
FORCEPROP 1 LAST PATH I79
J 0
(-6750 2625);
DISPLAY 0.978723 (-6750 2625);
PAINT WHITE (-6750 2625);
DISPLAY INVISIBLE (-6750 2625);
FORCEPROP 2 LAST SEC 1
J 0
(-6750 2675);
DISPLAY 0.680851 (-6750 2675);
PAINT MONO (-6750 2675);
DISPLAY INVISIBLE (-6750 2675);
FORCEPROP 0 LAST SEC_TYPE 0402
J 0
(-6725 2650);
DISPLAY 1.021277 (-6725 2650);
PAINT ORANGE (-6725 2650);
DISPLAY INVISIBLE (-6725 2650);
FORCEADD OFFPAGE..2
(-5475 2475);
FORCEPROP 2 LAST $XR0 146 
J 0
(-5286 2475);
DISPLAY 0.638298 (-5286 2475);
PAINT MONO (-5286 2475);
FORCEPROP 2 LAST $XR1 151 
J 0
(-5286 2475);
DISPLAY 0.638298 (-5286 2475);
PAINT MONO (-5286 2475);
FORCEPROP 1 LAST COMMENT_BODY TRUE
J 0
(-5520 2380);
DISPLAY 0.872340 (-5520 2380);
PAINT GREEN (-5520 2380);
DISPLAY INVISIBLE (-5520 2380);
FORCEPROP 2 LAST CDS_LIB mstr_standard
J 0
(-5475 2475);
PAINT ORANGE (-5475 2475);
DISPLAY INVISIBLE (-5475 2475);
FORCEPROP 1 LAST OFFPAGE TRUE
J 0
(-5150 2350);
DISPLAY 0.872340 (-5150 2350);
PAINT GREEN (-5150 2350);
DISPLAY INVISIBLE (-5150 2350);
FORCEPROP 2 LAST PATH I85
J 0
(-5300 2550);
DISPLAY 1.021277 (-5300 2550);
PAINT ORANGE (-5300 2550);
DISPLAY INVISIBLE (-5300 2550);
FORCEADD OFFPAGE..2
(-5475 2025);
FORCEPROP 2 LAST $XR0 151 
J 0
(-5286 2025);
DISPLAY 0.638298 (-5286 2025);
PAINT MONO (-5286 2025);
FORCEPROP 2 LAST $XR1 146 
J 0
(-5286 2025);
DISPLAY 0.638298 (-5286 2025);
PAINT MONO (-5286 2025);
FORCEPROP 1 LAST COMMENT_BODY TRUE
J 0
(-5520 1930);
DISPLAY 0.872340 (-5520 1930);
PAINT GREEN (-5520 1930);
DISPLAY INVISIBLE (-5520 1930);
FORCEPROP 1 LAST OFFPAGE TRUE
J 0
(-5150 1900);
DISPLAY 0.872340 (-5150 1900);
PAINT GREEN (-5150 1900);
DISPLAY INVISIBLE (-5150 1900);
FORCEPROP 2 LAST CDS_LIB mstr_standard
J 0
(-5475 2025);
PAINT ORANGE (-5475 2025);
DISPLAY INVISIBLE (-5475 2025);
FORCEPROP 2 LAST PATH I87
J 0
(-5300 2100);
DISPLAY 1.021277 (-5300 2100);
PAINT ORANGE (-5300 2100);
DISPLAY INVISIBLE (-5300 2100);
FORCEADD OFFPAGE..2
(-5475 1600);
FORCEPROP 2 LAST $XR0 145 
J 0
(-5286 1600);
DISPLAY 0.638298 (-5286 1600);
PAINT MONO (-5286 1600);
FORCEPROP 1 LAST OFFPAGE TRUE
J 0
(-5150 1475);
DISPLAY 0.872340 (-5150 1475);
PAINT GREEN (-5150 1475);
DISPLAY INVISIBLE (-5150 1475);
FORCEPROP 1 LAST COMMENT_BODY TRUE
J 0
(-5520 1505);
DISPLAY 0.872340 (-5520 1505);
PAINT GREEN (-5520 1505);
DISPLAY INVISIBLE (-5520 1505);
FORCEPROP 2 LAST CDS_LIB mstr_standard
J 0
(-5475 1600);
PAINT ORANGE (-5475 1600);
DISPLAY INVISIBLE (-5475 1600);
FORCEPROP 2 LAST PATH I89
J 0
(-5300 1675);
DISPLAY 1.021277 (-5300 1675);
PAINT ORANGE (-5300 1675);
DISPLAY INVISIBLE (-5300 1675);
FORCEADD OFFPAGE..2
(-5475 1175);
FORCEPROP 2 LAST $XR0 147 
J 0
(-5286 1175);
DISPLAY 0.638298 (-5286 1175);
PAINT MONO (-5286 1175);
FORCEPROP 1 LAST COMMENT_BODY TRUE
J 0
(-5520 1080);
DISPLAY 0.872340 (-5520 1080);
PAINT GREEN (-5520 1080);
DISPLAY INVISIBLE (-5520 1080);
FORCEPROP 2 LAST CDS_LIB mstr_standard
J 0
(-5475 1175);
PAINT ORANGE (-5475 1175);
DISPLAY INVISIBLE (-5475 1175);
FORCEPROP 1 LAST OFFPAGE TRUE
J 0
(-5150 1050);
DISPLAY 0.872340 (-5150 1050);
PAINT GREEN (-5150 1050);
DISPLAY INVISIBLE (-5150 1050);
FORCEPROP 2 LAST PATH I91
J 0
(-5300 1250);
DISPLAY 1.021277 (-5300 1250);
PAINT ORANGE (-5300 1250);
DISPLAY INVISIBLE (-5300 1250);
FORCEADD RES..1
(-6700 2025);
FORCEPROP 1 LAST WATTAGE 1/16W
J 2
(-6800 1975);
DISPLAY 0.617021 (-6800 1975);
PAINT SKYBLUE (-6800 1975);
FORCEPROP 1 LAST TOLERANCE 5%
J 0
(-6775 1975);
DISPLAY 0.617021 (-6775 1975);
PAINT SKYBLUE (-6775 1975);
FORCEPROP 1 LAST MATERIAL CHIP
J 0
(-6700 1975);
DISPLAY 0.617021 (-6700 1975);
PAINT SKYBLUE (-6700 1975);
FORCEPROP 1 LAST PACK_TYPE 0402
J 0
(-6600 1975);
DISPLAY 0.617021 (-6600 1975);
PAINT SKYBLUE (-6600 1975);
FORCEPROP 1 LASTPIN (-6800 2025) $PN 1
J 0
(-6788 2037);
DISPLAY 0.617021 (-6788 2037);
PAINT ORANGE (-6788 2037);
FORCEPROP 1 LASTPIN (-6600 2025) $PN 2
J 0
(-6638 2037);
DISPLAY 0.617021 (-6638 2037);
PAINT ORANGE (-6638 2037);
FORCEPROP 1 LAST VALUE 0.0
J 2
(-6800 2025);
DISPLAY 0.617021 (-6800 2025);
PAINT SKYBLUE (-6800 2025);
FORCEPROP 1 LAST LOCATION R9G29
J 0
(-6750 2075);
DISPLAY 0.617021 (-6750 2075);
PAINT AQUA (-6750 2075);
FORCEPROP 1 LAST PART_NUMBER G21497-005
J 0
(-6850 2125);
DISPLAY 0.617021 (-6850 2125);
PAINT BLUE (-6850 2125);
FORCEPROP 2 LAST CDS_LIB mstr_discrete
J 0
(-6700 2025);
PAINT ORANGE (-6700 2025);
DISPLAY INVISIBLE (-6700 2025);
FORCEPROP 1 LAST PATH I92
J 0
(-6750 2175);
DISPLAY 0.978723 (-6750 2175);
PAINT WHITE (-6750 2175);
DISPLAY INVISIBLE (-6750 2175);
FORCEPROP 2 LAST SEC 1
J 0
(-6750 2225);
DISPLAY 0.680851 (-6750 2225);
PAINT MONO (-6750 2225);
DISPLAY INVISIBLE (-6750 2225);
FORCEPROP 2 LAST SEC_TYPE 0402
J 0
(-6750 2225);
DISPLAY 1.021277 (-6750 2225);
PAINT ORANGE (-6750 2225);
DISPLAY INVISIBLE (-6750 2225);
FORCEADD RES..1
(-6700 1600);
FORCEPROP 1 LAST WATTAGE 1/16W
J 2
(-6800 1550);
DISPLAY 0.617021 (-6800 1550);
PAINT SKYBLUE (-6800 1550);
FORCEPROP 1 LAST VALUE 0.0
J 2
(-6800 1600);
DISPLAY 0.617021 (-6800 1600);
PAINT SKYBLUE (-6800 1600);
FORCEPROP 1 LASTPIN (-6800 1600) $PN 1
J 0
(-6788 1612);
DISPLAY 0.617021 (-6788 1612);
PAINT ORANGE (-6788 1612);
FORCEPROP 1 LAST TOLERANCE 5%
J 0
(-6775 1550);
DISPLAY 0.617021 (-6775 1550);
PAINT SKYBLUE (-6775 1550);
FORCEPROP 1 LAST MATERIAL CHIP
J 0
(-6700 1550);
DISPLAY 0.617021 (-6700 1550);
PAINT SKYBLUE (-6700 1550);
FORCEPROP 1 LAST PART_NUMBER G21497-005
J 0
(-6850 1700);
DISPLAY 0.617021 (-6850 1700);
PAINT BLUE (-6850 1700);
FORCEPROP 1 LAST LOCATION R1U54
J 0
(-6750 1650);
DISPLAY 0.617021 (-6750 1650);
PAINT AQUA (-6750 1650);
FORCEPROP 1 LASTPIN (-6600 1600) $PN 2
J 0
(-6638 1612);
DISPLAY 0.617021 (-6638 1612);
PAINT ORANGE (-6638 1612);
FORCEPROP 1 LAST PACK_TYPE 0402
J 0
(-6600 1550);
DISPLAY 0.617021 (-6600 1550);
PAINT SKYBLUE (-6600 1550);
FORCEPROP 2 LAST CDS_LIB mstr_discrete
J 0
(-6700 1600);
PAINT ORANGE (-6700 1600);
DISPLAY INVISIBLE (-6700 1600);
FORCEPROP 1 LAST PATH I93
J 0
(-6750 1750);
DISPLAY 0.978723 (-6750 1750);
PAINT WHITE (-6750 1750);
DISPLAY INVISIBLE (-6750 1750);
FORCEPROP 2 LAST SEC 1
J 0
(-6750 1800);
DISPLAY 0.680851 (-6750 1800);
PAINT MONO (-6750 1800);
DISPLAY INVISIBLE (-6750 1800);
FORCEPROP 2 LAST SEC_TYPE 0402
J 0
(-6750 1800);
DISPLAY 1.021277 (-6750 1800);
PAINT ORANGE (-6750 1800);
DISPLAY INVISIBLE (-6750 1800);
FORCEADD RES..1
(-6700 1175);
FORCEPROP 1 LAST WATTAGE 1/16W
J 2
(-6800 1125);
DISPLAY 0.617021 (-6800 1125);
PAINT SKYBLUE (-6800 1125);
FORCEPROP 1 LAST VALUE 0.0
J 2
(-6800 1175);
DISPLAY 0.617021 (-6800 1175);
PAINT SKYBLUE (-6800 1175);
FORCEPROP 1 LASTPIN (-6800 1175) $PN 1
J 0
(-6788 1187);
DISPLAY 0.617021 (-6788 1187);
PAINT ORANGE (-6788 1187);
FORCEPROP 1 LAST TOLERANCE 5%
J 0
(-6775 1125);
DISPLAY 0.617021 (-6775 1125);
PAINT SKYBLUE (-6775 1125);
FORCEPROP 1 LAST MATERIAL CHIP
J 0
(-6700 1125);
DISPLAY 0.617021 (-6700 1125);
PAINT SKYBLUE (-6700 1125);
FORCEPROP 1 LAST PART_NUMBER G21497-005
J 0
(-6850 1275);
DISPLAY 0.617021 (-6850 1275);
PAINT BLUE (-6850 1275);
FORCEPROP 1 LAST LOCATION R2U46
J 0
(-6750 1225);
DISPLAY 0.617021 (-6750 1225);
PAINT AQUA (-6750 1225);
FORCEPROP 1 LASTPIN (-6600 1175) $PN 2
J 0
(-6638 1187);
DISPLAY 0.617021 (-6638 1187);
PAINT ORANGE (-6638 1187);
FORCEPROP 1 LAST PACK_TYPE 0402
J 0
(-6600 1125);
DISPLAY 0.617021 (-6600 1125);
PAINT SKYBLUE (-6600 1125);
FORCEPROP 2 LAST CDS_LIB mstr_discrete
J 0
(-6700 1175);
PAINT ORANGE (-6700 1175);
DISPLAY INVISIBLE (-6700 1175);
FORCEPROP 2 LAST SEC 1
J 0
(-6750 1375);
DISPLAY 0.680851 (-6750 1375);
PAINT MONO (-6750 1375);
DISPLAY INVISIBLE (-6750 1375);
FORCEPROP 1 LAST PATH I94
J 0
(-6750 1325);
DISPLAY 0.978723 (-6750 1325);
PAINT WHITE (-6750 1325);
DISPLAY INVISIBLE (-6750 1325);
FORCEPROP 2 LAST SEC_TYPE 0402
J 0
(-6750 1375);
DISPLAY 1.021277 (-6750 1375);
PAINT ORANGE (-6750 1375);
DISPLAY INVISIBLE (-6750 1375);
FORCEADD RES..1
(-6700 2275);
FORCEPROP 1 LAST WATTAGE 1/16W
J 2
(-6800 2225);
DISPLAY 0.617021 (-6800 2225);
PAINT SKYBLUE (-6800 2225);
FORCEPROP 1 LAST VALUE 0.0
J 2
(-6800 2275);
DISPLAY 0.617021 (-6800 2275);
PAINT SKYBLUE (-6800 2275);
FORCEPROP 1 LAST TOLERANCE 5%
J 0
(-6775 2225);
DISPLAY 0.617021 (-6775 2225);
PAINT SKYBLUE (-6775 2225);
FORCEPROP 1 LAST PART_NUMBER G21497-005
J 0
(-6850 2375);
DISPLAY 0.617021 (-6850 2375);
PAINT BLUE (-6850 2375);
FORCEPROP 1 LAST LOCATION R3N30
J 0
(-6750 2325);
DISPLAY 0.617021 (-6750 2325);
PAINT AQUA (-6750 2325);
FORCEPROP 1 LAST MATERIAL EMPTY
J 0
(-6700 2225);
DISPLAY 0.617021 (-6700 2225);
PAINT RED (-6700 2225);
FORCEPROP 1 LAST PACK_TYPE 0402
J 0
(-6550 2225);
DISPLAY 0.617021 (-6550 2225);
PAINT SKYBLUE (-6550 2225);
FORCEPROP 1 LASTPIN (-6800 2275) $PN 1
J 0
(-6788 2287);
DISPLAY 0.787234 (-6788 2287);
PAINT ORANGE (-6788 2287);
DISPLAY INVISIBLE (-6788 2287);
FORCEPROP 2 LAST CDS_LIB mstr_discrete
J 0
(-6700 2275);
PAINT ORANGE (-6700 2275);
DISPLAY INVISIBLE (-6700 2275);
FORCEPROP 1 LAST PATH I95
J 0
(-6750 2425);
DISPLAY 0.978723 (-6750 2425);
PAINT WHITE (-6750 2425);
DISPLAY INVISIBLE (-6750 2425);
FORCEPROP 2 LAST $SEC 1
J 0
(-6750 2475);
PAINT MONO (-6750 2475);
DISPLAY INVISIBLE (-6750 2475);
FORCEPROP 2 LAST CDS_SEC 1
J 0
(-6750 2475);
PAINT MONO (-6750 2475);
DISPLAY INVISIBLE (-6750 2475);
FORCEPROP 1 LASTPIN (-6600 2275) $PN 2
J 0
(-6638 2287);
DISPLAY 0.787234 (-6638 2287);
PAINT ORANGE (-6638 2287);
DISPLAY INVISIBLE (-6638 2287);
FORCEADD OFFPAGE..2
(-5475 2275);
FORCEPROP 2 LAST $XR0 121 
J 0
(-5286 2275);
DISPLAY 0.638298 (-5286 2275);
PAINT MONO (-5286 2275);
FORCEPROP 1 LAST COMMENT_BODY TRUE
J 0
(-5520 2180);
DISPLAY 0.872340 (-5520 2180);
PAINT GREEN (-5520 2180);
DISPLAY INVISIBLE (-5520 2180);
FORCEPROP 2 LAST CDS_LIB mstr_standard
J 0
(-5475 2275);
PAINT ORANGE (-5475 2275);
DISPLAY INVISIBLE (-5475 2275);
FORCEPROP 1 LAST OFFPAGE TRUE
J 0
(-5150 2150);
DISPLAY 0.872340 (-5150 2150);
PAINT GREEN (-5150 2150);
DISPLAY INVISIBLE (-5150 2150);
FORCEPROP 2 LAST PATH I96
J 0
(-5300 2350);
DISPLAY 1.021277 (-5300 2350);
PAINT ORANGE (-5300 2350);
DISPLAY INVISIBLE (-5300 2350);
FORCEADD OFFPAGE..2
(-5475 1825);
FORCEPROP 2 LAST $XR0 121 
J 0
(-5286 1825);
DISPLAY 0.638298 (-5286 1825);
PAINT MONO (-5286 1825);
FORCEPROP 1 LAST COMMENT_BODY TRUE
J 0
(-5520 1730);
DISPLAY 0.872340 (-5520 1730);
PAINT GREEN (-5520 1730);
DISPLAY INVISIBLE (-5520 1730);
FORCEPROP 2 LAST CDS_LIB mstr_standard
J 0
(-5475 1825);
PAINT ORANGE (-5475 1825);
DISPLAY INVISIBLE (-5475 1825);
FORCEPROP 1 LAST OFFPAGE TRUE
J 0
(-5150 1700);
DISPLAY 0.872340 (-5150 1700);
PAINT GREEN (-5150 1700);
DISPLAY INVISIBLE (-5150 1700);
FORCEPROP 2 LAST PATH I97
J 0
(-5300 1900);
DISPLAY 1.021277 (-5300 1900);
PAINT ORANGE (-5300 1900);
DISPLAY INVISIBLE (-5300 1900);
FORCEADD RES..1
(-6700 1825);
FORCEPROP 1 LAST WATTAGE 1/16W
J 2
(-6800 1775);
DISPLAY 0.617021 (-6800 1775);
PAINT SKYBLUE (-6800 1775);
FORCEPROP 1 LAST TOLERANCE 5%
J 0
(-6775 1775);
DISPLAY 0.617021 (-6775 1775);
PAINT SKYBLUE (-6775 1775);
FORCEPROP 1 LAST VALUE 0.0
J 2
(-6800 1825);
DISPLAY 0.617021 (-6800 1825);
PAINT SKYBLUE (-6800 1825);
FORCEPROP 1 LAST LOCATION R9G30
J 0
(-6750 1875);
DISPLAY 0.617021 (-6750 1875);
PAINT AQUA (-6750 1875);
FORCEPROP 1 LAST PART_NUMBER G21497-005
J 0
(-6850 1925);
DISPLAY 0.617021 (-6850 1925);
PAINT BLUE (-6850 1925);
FORCEPROP 1 LAST MATERIAL EMPTY
J 0
(-6700 1775);
DISPLAY 0.617021 (-6700 1775);
PAINT RED (-6700 1775);
FORCEPROP 1 LAST PACK_TYPE 0402
J 0
(-6550 1775);
DISPLAY 0.617021 (-6550 1775);
PAINT SKYBLUE (-6550 1775);
FORCEPROP 1 LASTPIN (-6800 1825) $PN 1
J 0
(-6788 1837);
DISPLAY 0.787234 (-6788 1837);
PAINT ORANGE (-6788 1837);
DISPLAY INVISIBLE (-6788 1837);
FORCEPROP 2 LAST CDS_LIB mstr_discrete
J 0
(-6700 1825);
PAINT ORANGE (-6700 1825);
DISPLAY INVISIBLE (-6700 1825);
FORCEPROP 1 LAST PATH I98
J 0
(-6750 1975);
DISPLAY 0.978723 (-6750 1975);
PAINT WHITE (-6750 1975);
DISPLAY INVISIBLE (-6750 1975);
FORCEPROP 1 LASTPIN (-6600 1825) $PN 2
J 0
(-6638 1837);
DISPLAY 0.787234 (-6638 1837);
PAINT ORANGE (-6638 1837);
DISPLAY INVISIBLE (-6638 1837);
FORCEPROP 2 LAST $SEC 1
J 0
(-6750 2025);
PAINT MONO (-6750 2025);
DISPLAY INVISIBLE (-6750 2025);
FORCEPROP 2 LAST CDS_SEC 1
J 0
(-6750 2025);
PAINT MONO (-6750 2025);
DISPLAY INVISIBLE (-6750 2025);
FORCEADD OFFPAGE..2
(-5475 1400);
FORCEPROP 2 LAST $XR0 121 
J 0
(-5286 1400);
DISPLAY 0.638298 (-5286 1400);
PAINT MONO (-5286 1400);
FORCEPROP 2 LAST CDS_LIB mstr_standard
J 0
(-5475 1400);
PAINT ORANGE (-5475 1400);
DISPLAY INVISIBLE (-5475 1400);
FORCEPROP 1 LAST COMMENT_BODY TRUE
J 0
(-5520 1305);
DISPLAY 0.872340 (-5520 1305);
PAINT GREEN (-5520 1305);
DISPLAY INVISIBLE (-5520 1305);
FORCEPROP 1 LAST OFFPAGE TRUE
J 0
(-5150 1275);
DISPLAY 0.872340 (-5150 1275);
PAINT GREEN (-5150 1275);
DISPLAY INVISIBLE (-5150 1275);
FORCEPROP 2 LAST PATH I99
J 0
(-5300 1475);
DISPLAY 1.021277 (-5300 1475);
PAINT ORANGE (-5300 1475);
DISPLAY INVISIBLE (-5300 1475);
FORCEADD DNS..2
(-6695 1395);
PAINT RED (-6695 1395);
FORCEPROP 1 LAST COMMENT_BODY TRUE
R 1
J 0
(-6620 1170);
DISPLAY 0.872340 (-6620 1170);
PAINT GREEN (-6620 1170);
DISPLAY INVISIBLE (-6620 1170);
FORCEPROP 2 LAST CDS_LIB mstr_misc
J 0
(-6695 1395);
PAINT ORANGE (-6695 1395);
DISPLAY INVISIBLE (-6695 1395);
FORCEADD CAD_NOTE..1
(-2375 3550);
FORCEPROP 0 LAST L1 USE SHARED PADS WITH 0OHM
J 0
(-2525 3450);
DISPLAY 0.617021 (-2525 3450);
PAINT WHITE (-2525 3450);
FORCEPROP 0 LAST L2 STEERING RESISTORS
J 0
(-2525 3400);
DISPLAY 0.638298 (-2525 3400);
PAINT ORANGE (-2525 3400);
FORCEPROP 2 LAST CDS_LIB mstr_symbols
J 0
(-2375 3550);
PAINT ORANGE (-2375 3550);
DISPLAY INVISIBLE (-2375 3550);
FORCEPROP 1 LAST COMMENT_BODY TRUE
J 0
(-2350 3650);
DISPLAY 1.319149 (-2350 3650);
PAINT WHITE (-2350 3650);
DISPLAY INVISIBLE (-2350 3650);
FORCEADD DNS..2
(-6695 970);
PAINT RED (-6695 970);
FORCEPROP 1 LAST COMMENT_BODY TRUE
R 1
J 0
(-6620 745);
DISPLAY 0.872340 (-6620 745);
PAINT GREEN (-6620 745);
DISPLAY INVISIBLE (-6620 745);
FORCEPROP 2 LAST CDS_LIB mstr_misc
J 0
(-6695 970);
PAINT ORANGE (-6695 970);
DISPLAY INVISIBLE (-6695 970);
FORCEADD CAD_NOTE..1
(-6725 725);
FORCEPROP 0 LAST L1 USE SHARED PADS WITH
J 0
(-6875 625);
DISPLAY 0.617021 (-6875 625);
PAINT WHITE (-6875 625);
FORCEPROP 0 LAST L2 33.2OHM RESISTORS
J 0
(-6875 575);
DISPLAY 0.638298 (-6875 575);
PAINT ORANGE (-6875 575);
FORCEPROP 2 LAST CDS_LIB mstr_symbols
J 0
(-6725 725);
PAINT ORANGE (-6725 725);
DISPLAY INVISIBLE (-6725 725);
FORCEPROP 1 LAST COMMENT_BODY TRUE
J 0
(-6700 825);
DISPLAY 1.319149 (-6700 825);
PAINT WHITE (-6700 825);
DISPLAY INVISIBLE (-6700 825);
FORCEADD DESIGN_NOTE..1
(-5575 3450);
PAINT PURPLE (-5575 3450);
FORCEPROP 0 LAST L3 VREF IS SET AT 2/3 OF VCCIO
J 0
(-5775 3225);
DISPLAY 0.808511 (-5775 3225);
PAINT VIOLET (-5775 3225);
FORCEPROP 0 LAST L1 THE GTL2014 IS BEING USED AS GTL TO LVTTL CONVERTER, SO
J 0
(-5775 3325);
DISPLAY 0.808511 (-5775 3325);
PAINT VIOLET (-5775 3325);
FORCEPROP 0 LAST L2 THE PINS 'BX' ARE INPUTS & 'AX' OUTPUTS ARE PUSH-PULL.
J 0
(-5775 3275);
DISPLAY 0.808511 (-5775 3275);
PAINT VIOLET (-5775 3275);
FORCEPROP 1 LAST COMMENT_BODY TRUE
J 0
(-5550 3550);
DISPLAY 1.319149 (-5550 3550);
PAINT GREEN (-5550 3550);
DISPLAY INVISIBLE (-5550 3550);
FORCEPROP 2 LAST CDS_LIB mstr_symbols
J 0
(-5575 3450);
PAINT ORANGE (-5575 3450);
DISPLAY INVISIBLE (-5575 3450);
FORCEADD CAD_NOTE..1
(-6400 3425);
FORCEPROP 0 LAST L1 USE SHARED PADS FOR 0OHM
J 0
(-6550 3325);
DISPLAY 0.617021 (-6550 3325);
PAINT WHITE (-6550 3325);
FORCEPROP 0 LAST L2 STEERING RESISTORS
J 0
(-6550 3275);
DISPLAY 0.638298 (-6550 3275);
PAINT ORANGE (-6550 3275);
FORCEPROP 1 LAST COMMENT_BODY TRUE
J 0
(-6375 3525);
DISPLAY 1.319149 (-6375 3525);
PAINT WHITE (-6375 3525);
DISPLAY INVISIBLE (-6375 3525);
FORCEPROP 2 LAST CDS_LIB mstr_symbols
J 0
(-6400 3425);
PAINT ORANGE (-6400 3425);
DISPLAY INVISIBLE (-6400 3425);
FORCEADD DESIGN_NOTE..1
(-4000 2450);
FORCEPROP 2 LAST CDS_LIB mstr_symbols
J 0
(-4000 2450);
PAINT ORANGE (-4000 2450);
DISPLAY INVISIBLE (-4000 2450);
FORCEPROP 1 LAST COMMENT_BODY TRUE
J 0
(-3975 2550);
DISPLAY 0.978723 (-3975 2550);
PAINT ORANGE (-3975 2550);
DISPLAY INVISIBLE (-3975 2550);
FORCEADD CAD_NOTE..1
(-4000 3675);
FORCEPROP 0 LAST L1 USE SHARED PADS FOR 0OHM
J 0
(-4150 3575);
DISPLAY 0.617021 (-4150 3575);
PAINT WHITE (-4150 3575);
FORCEPROP 0 LAST L2 STEERING RESISTORS
J 0
(-4150 3525);
DISPLAY 0.638298 (-4150 3525);
PAINT ORANGE (-4150 3525);
FORCEPROP 1 LAST COMMENT_BODY TRUE
J 0
(-3975 3775);
DISPLAY 1.319149 (-3975 3775);
PAINT WHITE (-3975 3775);
DISPLAY INVISIBLE (-3975 3775);
FORCEPROP 2 LAST CDS_LIB mstr_symbols
J 0
(-4000 3675);
PAINT ORANGE (-4000 3675);
DISPLAY INVISIBLE (-4000 3675);
FORCEADD CAD_NOTE..1
(-8325 5175);
FORCEPROP 0 LAST L1 PLACE PU RESISTORS NEAR GTL2014
J 0
(-8475 5075);
DISPLAY 0.617021 (-8475 5075);
PAINT WHITE (-8475 5075);
FORCEPROP 1 LAST COMMENT_BODY TRUE
J 0
(-8300 5275);
DISPLAY 1.319149 (-8300 5275);
PAINT WHITE (-8300 5275);
DISPLAY INVISIBLE (-8300 5275);
FORCEPROP 2 LAST CDS_LIB mstr_symbols
J 0
(-8325 5175);
PAINT MONO (-8325 5175);
DISPLAY INVISIBLE (-8325 5175);
FORCEADD DNS..2
(-3145 4595);
PAINT RED (-3145 4595);
FORCEPROP 1 LAST COMMENT_BODY TRUE
R 1
J 0
(-3070 4370);
DISPLAY 0.872340 (-3070 4370);
PAINT GREEN (-3070 4370);
DISPLAY INVISIBLE (-3070 4370);
FORCEPROP 2 LAST CDS_LIB mstr_misc
J 0
(-3145 4595);
PAINT ORANGE (-3145 4595);
DISPLAY INVISIBLE (-3145 4595);
FORCEADD DNS..2
(-7170 4520);
PAINT RED (-7170 4520);
FORCEPROP 1 LAST COMMENT_BODY TRUE
R 1
J 0
(-7095 4295);
DISPLAY 0.872340 (-7095 4295);
PAINT GREEN (-7095 4295);
DISPLAY INVISIBLE (-7095 4295);
FORCEPROP 2 LAST CDS_LIB mstr_misc
J 0
(-7170 4520);
PAINT ORANGE (-7170 4520);
DISPLAY INVISIBLE (-7170 4520);
FORCEADD DNS..2
(-7445 4520);
PAINT RED (-7445 4520);
FORCEPROP 1 LAST COMMENT_BODY TRUE
R 1
J 0
(-7370 4295);
DISPLAY 0.872340 (-7370 4295);
PAINT GREEN (-7370 4295);
DISPLAY INVISIBLE (-7370 4295);
FORCEPROP 2 LAST CDS_LIB mstr_misc
J 0
(-7445 4520);
PAINT ORANGE (-7445 4520);
DISPLAY INVISIBLE (-7445 4520);
FORCEADD DNS..2
(-2845 4595);
PAINT RED (-2845 4595);
FORCEPROP 1 LAST COMMENT_BODY TRUE
R 1
J 0
(-2770 4370);
DISPLAY 0.872340 (-2770 4370);
PAINT GREEN (-2770 4370);
DISPLAY INVISIBLE (-2770 4370);
FORCEPROP 2 LAST CDS_LIB mstr_misc
J 0
(-2845 4595);
PAINT ORANGE (-2845 4595);
DISPLAY INVISIBLE (-2845 4595);
FORCEADD DNS..2
(-7170 3495);
PAINT RED (-7170 3495);
FORCEPROP 1 LAST COMMENT_BODY TRUE
R 1
J 0
(-7095 3270);
DISPLAY 0.872340 (-7095 3270);
PAINT GREEN (-7095 3270);
DISPLAY INVISIBLE (-7095 3270);
FORCEPROP 2 LAST CDS_LIB mstr_misc
J 0
(-7170 3495);
PAINT ORANGE (-7170 3495);
DISPLAY INVISIBLE (-7170 3495);
FORCEADD DNS..2
(-7445 3495);
PAINT RED (-7445 3495);
FORCEPROP 1 LAST COMMENT_BODY TRUE
R 1
J 0
(-7370 3270);
DISPLAY 0.872340 (-7370 3270);
PAINT GREEN (-7370 3270);
DISPLAY INVISIBLE (-7370 3270);
FORCEPROP 2 LAST CDS_LIB mstr_misc
J 0
(-7445 3495);
PAINT ORANGE (-7445 3495);
DISPLAY INVISIBLE (-7445 3495);
FORCEADD DNS..2
(-3170 3420);
PAINT RED (-3170 3420);
FORCEPROP 1 LAST COMMENT_BODY TRUE
R 1
J 0
(-3095 3195);
DISPLAY 0.872340 (-3095 3195);
PAINT GREEN (-3095 3195);
DISPLAY INVISIBLE (-3095 3195);
FORCEPROP 2 LAST CDS_LIB mstr_misc
J 0
(-3170 3420);
PAINT ORANGE (-3170 3420);
DISPLAY INVISIBLE (-3170 3420);
FORCEADD DNS..2
(-2870 3420);
PAINT RED (-2870 3420);
FORCEPROP 1 LAST COMMENT_BODY TRUE
R 1
J 0
(-2795 3195);
DISPLAY 0.872340 (-2795 3195);
PAINT GREEN (-2795 3195);
DISPLAY INVISIBLE (-2795 3195);
FORCEPROP 2 LAST CDS_LIB mstr_misc
J 0
(-2870 3420);
PAINT ORANGE (-2870 3420);
DISPLAY INVISIBLE (-2870 3420);
FORCEADD DNS..2
(-6695 2270);
PAINT RED (-6695 2270);
FORCEPROP 1 LAST COMMENT_BODY TRUE
R 1
J 0
(-6620 2045);
DISPLAY 0.872340 (-6620 2045);
PAINT GREEN (-6620 2045);
DISPLAY INVISIBLE (-6620 2045);
FORCEPROP 2 LAST CDS_LIB mstr_misc
J 0
(-6695 2270);
PAINT ORANGE (-6695 2270);
DISPLAY INVISIBLE (-6695 2270);
FORCEADD DNS..2
(-6695 1820);
PAINT RED (-6695 1820);
FORCEPROP 1 LAST COMMENT_BODY TRUE
R 1
J 0
(-6620 1595);
DISPLAY 0.872340 (-6620 1595);
PAINT GREEN (-6620 1595);
DISPLAY INVISIBLE (-6620 1595);
FORCEPROP 2 LAST CDS_LIB mstr_misc
J 0
(-6695 1820);
PAINT ORANGE (-6695 1820);
DISPLAY INVISIBLE (-6695 1820);
FORCEADD CAD_NOTE..1
(-8675 2700);
FORCEPROP 0 LAST L2 CORRESPONDING CPU
J 0
(-8825 2550);
DISPLAY 0.638298 (-8825 2550);
PAINT ORANGE (-8825 2550);
FORCEPROP 0 LAST L1 PLACE PU RESISTORS NEAR
J 0
(-8825 2600);
DISPLAY 0.617021 (-8825 2600);
PAINT WHITE (-8825 2600);
FORCEPROP 2 LAST CDS_LIB mstr_symbols
J 0
(-8675 2700);
PAINT MONO (-8675 2700);
DISPLAY INVISIBLE (-8675 2700);
FORCEPROP 1 LAST COMMENT_BODY TRUE
J 0
(-8650 2800);
DISPLAY 1.319149 (-8650 2800);
PAINT WHITE (-8650 2800);
DISPLAY INVISIBLE (-8650 2800);
FORCEADD INTEL_CORP_BPAGE..1
(-1075 450);
FORCEPROP 1 LAST CDS_CON_LAST_MODIFIED Tue Dec 01 11:52:07 2015
J 0
(-2500 775);
DISPLAY 1.361702 (-2500 775);
PAINT GREEN (-2500 775);
DISPLAY INVISIBLE (-2500 775);
FORCEPROP 1 LAST CUSTOM_TXT_CDS <CURRENT_DESIGN_SHEET> OF <TOTAL_DESIGN_SHEETS>
J 0
(-1575 475);
PAINT GREEN (-1575 475);
FORCEPROP 1 LAST CUSTOM_TXT_CDS <CON_LAST_MODIFIED>
J 0
(-3000 800);
PAINT GREEN (-3000 800);
FORCEPROP 2 LAST CUSTOM_TXT_CDS <XR_PAGE_TITLE>
J 0
(-8965 5700);
DISPLAY 0.638298 (-8965 5700);
PAINT PINK (-8965 5700);
DISPLAY INVISIBLE (-8965 5700);
FORCEPROP 1 LAST SCH_TITLE MEMHOT LVT3 LEVEL TRANSLATION
J 0
(-9025 500);
DISPLAY 1.212766 (-9025 500);
PAINT ORANGE (-9025 500);
FORCEPROP 1 LAST SCH_ADDRESS1 2200 Mission College Blvd.
J 0
(-5050 575);
DISPLAY 0.617021 (-5050 575);
PAINT GREEN (-5050 575);
FORCEPROP 1 LAST SCH_ADDRESS2 P.O. BOX 58119
J 0
(-5050 525);
DISPLAY 0.617021 (-5050 525);
PAINT GREEN (-5050 525);
FORCEPROP 1 LAST SCH_ADDRESS3 Santa Clara, CA 95052-8119
J 0
(-5050 475);
DISPLAY 0.617021 (-5050 475);
PAINT GREEN (-5050 475);
FORCEPROP 1 LAST SCH_NUMBER H4694802
J 0
(-2375 600);
DISPLAY 1.212766 (-2375 600);
PAINT YELLOW (-2375 600);
FORCEPROP 1 LAST SCH_DEPT BESD
J 1
(-5525 550);
DISPLAY 1.212766 (-5525 550);
PAINT YELLOW (-5525 550);
FORCEPROP 1 LAST SCH_REV 2.420
J 0
(-1325 600);
DISPLAY 0.978723 (-1325 600);
PAINT YELLOW (-1325 600);
FORCEPROP 2 LAST PAGE_BORDER TRUE
J 0
(-8965 5700);
DISPLAY 0.851064 (-8965 5700);
PAINT PINK (-8965 5700);
DISPLAY INVISIBLE (-8965 5700);
FORCEPROP 1 LAST COMMENT_BODY TRUE
J 0
(-1063 462);
DISPLAY 0.617021 (-1063 462);
PAINT GREEN (-1063 462);
DISPLAY INVISIBLE (-1063 462);
FORCEPROP 2 LAST CDS_LIB mstr_symbols
J 0
(-1075 450);
DISPLAY 1.361702 (-1075 450);
PAINT ORANGE (-1075 450);
DISPLAY INVISIBLE (-1075 450);
FORCEPROP 2 LAST CDS_XR_PAGE_TITLE CR-152 : @BASEBOARD_FAB2_LIB.BASEBOARD_FAB2(SCH_1):PAGE152
J 0
(-8965 5700);
DISPLAY 0.638298 (-8965 5700);
PAINT PINK (-8965 5700);
DISPLAY INVISIBLE (-8965 5700);
WIRE 16 -1 (-5900 3750)(-5850 3750);
WIRE 16 -1 (-5900 3700)(-5900 3750);
WIRE 16 -1 (-5900 3700)(-5850 3700);
WIRE 16 -1 (-5900 3650)(-5900 3700);
WIRE 16 -1 (-5900 3650)(-5850 3650);
WIRE 16 -1 (-5900 3575)(-5900 3650);
WIRE 16 -1 (-4525 4500)(-4525 4550);
WIRE 16 -1 (-1775 2100)(-1775 2300);
WIRE 16 -1 (-2150 1500)(-2150 1375);
WIRE 16 -1 (-2150 1375)(-1775 1375);
WIRE 16 -1 (-1775 1375)(-1775 1500);
WIRE 16 -1 (-1775 1325)(-1775 1375);
WIRE 16 -1 (-3825 4175)(-3825 4200);
WIRE 16 -1 (-3825 4200)(-4250 4200);
WIRE 16 -1 (-4525 4750)(-4525 4825);
WIRE 16 -1 (-4525 4825)(-4775 4825);
WIRE 16 -1 (-4775 4825)(-4775 4350);
WIRE 16 -1 (-4775 4875)(-4775 4825);
WIRE 16 -1 (-4775 4350)(-4950 4350);
WIRE 16 -1 (-7875 4750)(-7875 4825);
WIRE 16 -1 (-7875 4825)(-7925 4825);
WIRE 16 -1 (-7925 4825)(-7975 4825);
WIRE 16 -1 (-7925 4825)(-7925 4900);
WIRE 16 -1 (-7975 4825)(-7975 4750);
WIRE 16 -1 (-8375 4825)(-8425 4825);
WIRE 16 -1 (-8375 4825)(-8325 4825);
WIRE 16 -1 (-8375 4825)(-8375 4900);
WIRE 16 -1 (-8425 4825)(-8425 4750);
WIRE 16 -1 (-8325 4750)(-8325 4825);
WIRE 16 -1 (-7800 3025)(-7800 3150);
WIRE 16 -1 (-7850 3025)(-7800 3025);
WIRE 16 -1 (-7900 3025)(-7850 3025);
WIRE 16 -1 (-7850 3025)(-7850 2975);
WIRE 16 -1 (-7900 3150)(-7900 3025);
WIRE 16 -1 (-8250 3025)(-8250 3175);
WIRE 16 -1 (-8300 3025)(-8250 3025);
WIRE 16 -1 (-8350 3025)(-8300 3025);
WIRE 16 -1 (-8300 2975)(-8300 3025);
WIRE 16 -1 (-8350 3175)(-8350 3025);
WIRE 16 2175 (-7600 4400)(-7600 5050);
WIRE 16 2175 (-8675 4400)(-7600 4400);
WIRE 16 2175 (-7600 5050)(-8675 5050);
WIRE 16 2175 (-8675 5050)(-8675 4400);
WIRE 16 -1 (-2350 4250)(-1625 4250);
FORCEPROP 2 LAST SIG_NAME H_CPU0_MEMABC_MEMHOT_LVT3_N
J 0
(-2210 4260);
DISPLAY 0.617021 (-2210 4260);
PAINT ORANGE (-2210 4260);
WIRE 16 -1 (-2850 4700)(-2850 5125);
WIRE 16 -1 (-7450 5125)(-2850 5125);
FORCEPROP 2 LAST SIG_NAME H_CPU0_MEMABC_MEMHOT_G_PCH_N
J 0
(-5860 5135);
DISPLAY 0.617021 (-5860 5135);
PAINT ORANGE (-5860 5135);
FORCEPROP 2 LASTPROP $XRERR UNIQUE?
J 0
(-6100 5135);
DISPLAY 0.638298 (-6100 5135);
PAINT MONO (-6100 5135);
DISPLAY INVISIBLE (-6100 5135);
WIRE 16 -1 (-7450 4625)(-7450 5125);
WIRE 16 2175 (-2600 4375)(-2250 4375);
WIRE 16 2175 (-2600 3625)(-2600 4375);
WIRE 16 2175 (-2250 4375)(-2250 3625);
WIRE 16 2175 (-2250 3625)(-2600 3625);
WIRE 16 -1 (-2850 4500)(-2850 4250);
WIRE 16 -1 (-2550 4250)(-2850 4250);
WIRE 16 -1 (-3275 4250)(-2850 4250);
FORCEPROP 2 LAST SIG_NAME H_CPU0_MEMABC_MEMHOT_LVT3_K_N
J 0
(-3250 4260);
DISPLAY 0.617021 (-3250 4260);
PAINT ORANGE (-3250 4260);
FORCEPROP 2 LASTPROP $XRERR UNIQUE?
J 0
(-3490 4260);
DISPLAY 0.638298 (-3490 4260);
PAINT MONO (-3490 4260);
DISPLAY INVISIBLE (-3490 4260);
WIRE 16 2175 (-2650 4800)(-3650 4800);
WIRE 16 2175 (-2650 3225)(-2650 4800);
WIRE 16 2175 (-3650 4800)(-3650 3225);
WIRE 16 2175 (-3650 3225)(-2650 3225);
WIRE 16 -1 (-3150 5075)(-3150 4700);
WIRE 16 -1 (-7175 5075)(-3150 5075);
FORCEPROP 2 LAST SIG_NAME H_CPU0_MEMDEF_MEMHOT_G_PCH_N
J 0
(-5860 5085);
DISPLAY 0.617021 (-5860 5085);
PAINT ORANGE (-5860 5085);
FORCEPROP 2 LASTPROP $XRERR UNIQUE?
J 0
(-6100 5085);
DISPLAY 0.638298 (-6100 5085);
PAINT MONO (-6100 5085);
DISPLAY INVISIBLE (-6100 5085);
WIRE 16 -1 (-7175 4625)(-7175 5075);
WIRE 16 -1 (-3600 4250)(-3475 4250);
WIRE 16 -1 (-3600 4250)(-3600 4050);
WIRE 16 -1 (-3600 4050)(-4950 4050);
FORCEPROP 2 LAST SIG_NAME H_CPU0_ABC_MEMHOT_LVT3_R_N
J 0
(-4860 4060);
DISPLAY 0.617021 (-4860 4060);
PAINT ORANGE (-4860 4060);
FORCEPROP 2 LASTPROP $XRERR UNIQUE?
J 0
(-5100 4060);
DISPLAY 0.638298 (-5100 4060);
PAINT MONO (-5100 4060);
DISPLAY INVISIBLE (-5100 4060);
WIRE 16 -1 (-3150 4500)(-3150 4075);
WIRE 16 -1 (-3150 4075)(-2550 4075);
WIRE 16 -1 (-3275 4075)(-3150 4075);
FORCEPROP 2 LAST SIG_NAME H_CPU0_MEMDEF_MEMHOT_LVT3_K_N
J 0
(-3250 4085);
DISPLAY 0.617021 (-3250 4085);
PAINT ORANGE (-3250 4085);
FORCEPROP 2 LASTPROP $XRERR UNIQUE?
J 0
(-3490 4085);
DISPLAY 0.638298 (-3490 4085);
PAINT MONO (-3490 4085);
DISPLAY INVISIBLE (-3490 4085);
WIRE 16 -1 (-1775 1900)(-1775 1800);
WIRE 16 -1 (-1775 1800)(-1775 1700);
WIRE 16 -1 (-2150 1800)(-1775 1800);
FORCEPROP 0 LAST VOLTAGE +0.7
J 0
(-1950 1850);
DISPLAY 1.021277 (-1950 1850);
PAINT SKYBLUE (-1950 1850);
DISPLAY INVISIBLE (-1950 1850);
WIRE 16 -1 (-2150 1700)(-2150 1800);
WIRE 16 -1 (-2600 1800)(-2150 1800);
FORCEPROP 2 LAST SIG_NAME P0V7_GTL2014_2
J 0
(-2535 1810);
DISPLAY 0.617021 (-2535 1810);
PAINT ORANGE (-2535 1810);
WIRE 16 -1 (-2350 4075)(-1625 4075);
FORCEPROP 2 LAST SIG_NAME H_CPU0_MEMDEF_MEMHOT_LVT3_N
J 0
(-2210 4085);
DISPLAY 0.617021 (-2210 4085);
PAINT ORANGE (-2210 4085);
WIRE 16 -1 (-2350 3900)(-1625 3900);
FORCEPROP 2 LAST SIG_NAME H_CPU1_MEMGHJ_MEMHOT_LVT3_N
J 0
(-2210 3910);
DISPLAY 0.617021 (-2210 3910);
PAINT ORANGE (-2210 3910);
WIRE 16 -1 (-2350 3725)(-1625 3725);
FORCEPROP 2 LAST SIG_NAME H_CPU1_MEMKLM_MEMHOT_LVT3_N
J 0
(-2210 3735);
DISPLAY 0.617021 (-2210 3735);
PAINT ORANGE (-2210 3735);
WIRE 16 -1 (-2875 3525)(-2875 3725);
WIRE 16 -1 (-2550 3725)(-2875 3725);
WIRE 16 -1 (-3275 3725)(-2875 3725);
FORCEPROP 2 LAST SIG_NAME H_CPU1_MEMKLM_MEMHOT_LVT3_K_N
J 0
(-3250 3735);
DISPLAY 0.617021 (-3250 3735);
PAINT ORANGE (-3250 3735);
FORCEPROP 2 LASTPROP $XRERR UNIQUE?
J 0
(-3490 3735);
DISPLAY 0.638298 (-3490 3735);
PAINT MONO (-3490 3735);
DISPLAY INVISIBLE (-3490 3735);
WIRE 16 -1 (-2875 3050)(-2875 3325);
WIRE 16 -1 (-7450 3050)(-2875 3050);
FORCEPROP 2 LAST SIG_NAME H_CPU1_MEMKLM_MEMHOT_G_PCH_N
J 0
(-5760 3060);
DISPLAY 0.617021 (-5760 3060);
PAINT ORANGE (-5760 3060);
FORCEPROP 2 LASTPROP $XRERR UNIQUE?
J 0
(-6000 3060);
DISPLAY 0.638298 (-6000 3060);
PAINT MONO (-6000 3060);
DISPLAY INVISIBLE (-6000 3060);
WIRE 16 -1 (-7450 3400)(-7450 3050);
WIRE 16 -1 (-3175 3900)(-2550 3900);
WIRE 16 -1 (-3275 3900)(-3175 3900);
FORCEPROP 2 LAST SIG_NAME H_CPU1_MEMGHJ_MEMHOT_LVT3_K_N
J 0
(-3250 3910);
DISPLAY 0.617021 (-3250 3910);
PAINT ORANGE (-3250 3910);
FORCEPROP 2 LASTPROP $XRERR UNIQUE?
J 0
(-3490 3910);
DISPLAY 0.638298 (-3490 3910);
PAINT MONO (-3490 3910);
DISPLAY INVISIBLE (-3490 3910);
WIRE 16 -1 (-3175 3900)(-3175 3525);
WIRE 16 -1 (-3525 4075)(-3475 4075);
WIRE 16 -1 (-3525 4000)(-3525 4075);
WIRE 16 -1 (-4950 4000)(-3525 4000);
FORCEPROP 2 LAST SIG_NAME H_CPU0_DEF_MEMHOT_LVT3_R_N
J 0
(-4860 4010);
DISPLAY 0.617021 (-4860 4010);
PAINT ORANGE (-4860 4010);
FORCEPROP 2 LASTPROP $XRERR UNIQUE?
J 0
(-5100 4010);
DISPLAY 0.638298 (-5100 4010);
PAINT MONO (-5100 4010);
DISPLAY INVISIBLE (-5100 4010);
WIRE 16 -1 (-3525 3950)(-3525 3900);
WIRE 16 -1 (-4950 3950)(-3525 3950);
FORCEPROP 2 LAST SIG_NAME H_CPU1_GHJ_MEMHOT_LVT3_R_N
J 0
(-4860 3960);
DISPLAY 0.617021 (-4860 3960);
PAINT ORANGE (-4860 3960);
FORCEPROP 2 LASTPROP $XRERR UNIQUE?
J 0
(-5100 3960);
DISPLAY 0.638298 (-5100 3960);
PAINT MONO (-5100 3960);
DISPLAY INVISIBLE (-5100 3960);
WIRE 16 -1 (-3525 3900)(-3475 3900);
WIRE 16 -1 (-3175 3100)(-3175 3325);
WIRE 16 -1 (-7175 3100)(-3175 3100);
FORCEPROP 2 LAST SIG_NAME H_CPU1_MEMGHJ_MEMHOT_G_PCH_N
J 0
(-5760 3110);
DISPLAY 0.617021 (-5760 3110);
PAINT ORANGE (-5760 3110);
FORCEPROP 2 LASTPROP $XRERR UNIQUE?
J 0
(-6000 3110);
DISPLAY 0.638298 (-6000 3110);
PAINT MONO (-6000 3110);
DISPLAY INVISIBLE (-6000 3110);
WIRE 16 -1 (-7175 3400)(-7175 3100);
WIRE 16 -1 (-3600 3725)(-3475 3725);
WIRE 16 -1 (-3600 3900)(-3600 3725);
WIRE 16 -1 (-4950 3900)(-3600 3900);
FORCEPROP 2 LAST SIG_NAME H_CPU1_KLM_MEMHOT_LVT3_R_N
J 0
(-4860 3910);
DISPLAY 0.617021 (-4860 3910);
PAINT ORANGE (-4860 3910);
FORCEPROP 2 LASTPROP $XRERR UNIQUE?
J 0
(-5100 3910);
DISPLAY 0.638298 (-5100 3910);
PAINT MONO (-5100 3910);
DISPLAY INVISIBLE (-5100 3910);
WIRE 16 -1 (-3625 2300)(-3625 2200);
WIRE 16 -1 (-3625 2300)(-3925 2300);
WIRE 16 -1 (-3625 2200)(-3625 1200);
WIRE 16 -1 (-4250 2200)(-3625 2200);
WIRE 16 -1 (-4250 2300)(-4250 2200);
WIRE 16 -1 (-4250 2200)(-4250 1200);
WIRE 16 -1 (-3625 1200)(-3925 1200);
WIRE 16 -1 (-3925 2300)(-3925 1200);
WIRE 16 -1 (-4250 2300)(-3925 2300);
WIRE 16 -1 (-4250 1200)(-3925 1200);
WIRE 16 -1 (-4450 4200)(-4950 4200);
FORCEPROP 2 LAST SIG_NAME PD_DIR_2
J 0
(-4860 4210);
DISPLAY 0.617021 (-4860 4210);
PAINT ORANGE (-4860 4210);
FORCEPROP 2 LASTPROP $XRERR UNIQUE?
J 0
(-5100 4210);
DISPLAY 0.638298 (-5100 4210);
PAINT MONO (-5100 4210);
DISPLAY INVISIBLE (-5100 4210);
WIRE 16 -1 (-4950 4300)(-4150 4300);
FORCEPROP 2 LAST SIG_NAME P0V7_GTL2014_2
J 0
(-4885 4310);
DISPLAY 0.617021 (-4885 4310);
PAINT ORANGE (-4885 4310);
WIRE 16 -1 (-6850 4225)(-6700 4225);
WIRE 16 -1 (-6700 4050)(-6700 4225);
WIRE 16 -1 (-5850 4050)(-6700 4050);
FORCEPROP 2 LAST SIG_NAME H_CPU0_MEMABC_MEMHOT_G_R_N
J 0
(-6535 4060);
DISPLAY 0.617021 (-6535 4060);
PAINT ORANGE (-6535 4060);
FORCEPROP 2 LASTPROP $XRERR UNIQUE?
J 0
(-6775 4060);
DISPLAY 0.638298 (-6775 4060);
PAINT MONO (-6775 4060);
DISPLAY INVISIBLE (-6775 4060);
WIRE 16 2175 (-6650 4725)(-7575 4725);
WIRE 16 2175 (-6650 3250)(-6650 4725);
WIRE 16 2175 (-7575 4725)(-7575 3250);
WIRE 16 2175 (-7575 3250)(-6650 3250);
WIRE 16 -1 (-7450 4425)(-7450 4225);
WIRE 16 -1 (-7050 4225)(-7450 4225);
WIRE 16 -1 (-7450 4225)(-7800 4225);
WIRE 16 -1 (-7875 4225)(-7800 4225);
WIRE 16 -1 (-7800 3350)(-7800 4225);
WIRE 16 -1 (-7875 4550)(-7875 4225);
WIRE 16 -1 (-8475 4225)(-7875 4225);
FORCEPROP 2 LAST SIG_NAME H_CPU0_MEMABC_MEMHOT_G_N
J 0
(-8460 4235);
DISPLAY 0.617021 (-8460 4235);
PAINT ORANGE (-8460 4235);
WIRE 16 -1 (-7975 4550)(-7975 4050);
WIRE 16 -1 (-7975 4050)(-7900 4050);
WIRE 16 -1 (-7975 4050)(-8475 4050);
FORCEPROP 2 LAST SIG_NAME H_CPU0_MEMDEF_MEMHOT_G_N
J 0
(-8460 4060);
DISPLAY 0.617021 (-8460 4060);
PAINT ORANGE (-8460 4060);
WIRE 16 -1 (-7175 4050)(-7900 4050);
WIRE 16 -1 (-7900 3350)(-7900 4050);
WIRE 16 -1 (-7175 4425)(-7175 4050);
WIRE 16 -1 (-7050 4050)(-7175 4050);
WIRE 16 -1 (-5850 3950)(-6750 3950);
FORCEPROP 2 LAST SIG_NAME H_CPU1_MEMGHJ_MEMHOT_G_R_N
J 0
(-6535 3960);
DISPLAY 0.617021 (-6535 3960);
PAINT ORANGE (-6535 3960);
FORCEPROP 2 LASTPROP $XRERR UNIQUE?
J 0
(-6775 3960);
DISPLAY 0.638298 (-6775 3960);
PAINT MONO (-6775 3960);
DISPLAY INVISIBLE (-6775 3960);
WIRE 16 -1 (-6750 3950)(-6750 3900);
WIRE 16 -1 (-6850 3900)(-6750 3900);
WIRE 16 -1 (-5850 4000)(-6750 4000);
FORCEPROP 2 LAST SIG_NAME H_CPU0_MEMDEF_MEMHOT_G_R_N
J 0
(-6535 4010);
DISPLAY 0.617021 (-6535 4010);
PAINT ORANGE (-6535 4010);
FORCEPROP 2 LASTPROP $XRERR UNIQUE?
J 0
(-6775 4010);
DISPLAY 0.638298 (-6775 4010);
PAINT MONO (-6775 4010);
DISPLAY INVISIBLE (-6775 4010);
WIRE 16 -1 (-6750 4000)(-6750 4050);
WIRE 16 -1 (-6850 4050)(-6750 4050);
WIRE 16 -1 (-5850 3900)(-6700 3900);
FORCEPROP 2 LAST SIG_NAME H_CPU1_MEMKLM_MEMHOT_G_R_N
J 0
(-6535 3910);
DISPLAY 0.617021 (-6535 3910);
PAINT ORANGE (-6535 3910);
FORCEPROP 2 LASTPROP $XRERR UNIQUE?
J 0
(-6775 3910);
DISPLAY 0.638298 (-6775 3910);
PAINT MONO (-6775 3910);
DISPLAY INVISIBLE (-6775 3910);
WIRE 16 -1 (-6700 3900)(-6700 3750);
WIRE 16 -1 (-6850 3750)(-6700 3750);
WIRE 16 -1 (-6600 1400)(-5525 1400);
FORCEPROP 2 LAST SIG_NAME H_CPU1_MEMGHJ_MEMHOT_PCH_N
J 0
(-6375 1410);
DISPLAY 0.617021 (-6375 1410);
PAINT ORANGE (-6375 1410);
WIRE 16 -1 (-6600 1600)(-5525 1600);
FORCEPROP 2 LAST SIG_NAME H_CPU1_MEMGHJ_MEMHOT_LVT3_BMC_N
J 0
(-6375 1610);
DISPLAY 0.617021 (-6375 1610);
PAINT ORANGE (-6375 1610);
WIRE 16 -1 (-6600 975)(-5525 975);
FORCEPROP 2 LAST SIG_NAME H_CPU1_MEMKLM_MEMHOT_PCH_N
J 0
(-6375 985);
DISPLAY 0.617021 (-6375 985);
PAINT ORANGE (-6375 985);
WIRE 16 -1 (-6600 2475)(-5525 2475);
FORCEPROP 2 LAST SIG_NAME H_CPU0_MEMABC_MEMHOT_LVT3_BMC_N
J 0
(-6375 2485);
DISPLAY 0.617021 (-6375 2485);
PAINT ORANGE (-6375 2485);
WIRE 16 -1 (-6600 2025)(-5525 2025);
FORCEPROP 2 LAST SIG_NAME H_CPU0_MEMDEF_MEMHOT_LVT3_BMC_N
J 0
(-6375 2035);
DISPLAY 0.617021 (-6375 2035);
PAINT ORANGE (-6375 2035);
WIRE 16 -1 (-6600 1175)(-5525 1175);
FORCEPROP 2 LAST SIG_NAME H_CPU1_MEMKLM_MEMHOT_LVT3_BMC_N
J 0
(-6375 1185);
DISPLAY 0.617021 (-6375 1185);
PAINT ORANGE (-6375 1185);
WIRE 16 -1 (-6600 2275)(-5525 2275);
FORCEPROP 2 LAST SIG_NAME H_CPU0_MEMABC_MEMHOT_PCH_N
J 0
(-6375 2285);
DISPLAY 0.617021 (-6375 2285);
PAINT ORANGE (-6375 2285);
WIRE 16 -1 (-6600 1825)(-5525 1825);
FORCEPROP 2 LAST SIG_NAME H_CPU0_MEMDEF_MEMHOT_PCH_N
J 0
(-6375 1835);
DISPLAY 0.617021 (-6375 1835);
PAINT ORANGE (-6375 1835);
WIRE 16 2175 (-6925 2650)(-6425 2650);
WIRE 16 2175 (-6925 825)(-6925 2650);
WIRE 16 2175 (-6425 2650)(-6425 825);
WIRE 16 2175 (-6425 825)(-6925 825);
WIRE 16 -1 (-6800 2275)(-7025 2275);
WIRE 16 -1 (-7025 2275)(-7025 2475);
WIRE 16 -1 (-7025 2475)(-6800 2475);
WIRE 16 -1 (-7775 2475)(-7025 2475);
FORCEPROP 2 LAST SIG_NAME H_CPU0_MEMABC_MEMHOT_LVT3_N
J 0
(-7735 2485);
DISPLAY 0.617021 (-7735 2485);
PAINT ORANGE (-7735 2485);
WIRE 16 -1 (-7450 3600)(-7450 3750);
WIRE 16 -1 (-7050 3750)(-7450 3750);
WIRE 16 -1 (-7450 3750)(-8350 3750);
WIRE 16 -1 (-8425 3750)(-8350 3750);
WIRE 16 -1 (-8350 3750)(-8350 3375);
WIRE 16 -1 (-8425 4550)(-8425 3750);
WIRE 16 -1 (-8475 3750)(-8425 3750);
FORCEPROP 2 LAST SIG_NAME H_CPU1_MEMKLM_MEMHOT_G_N
J 0
(-8460 3760);
DISPLAY 0.617021 (-8460 3760);
PAINT ORANGE (-8460 3760);
WIRE 16 -1 (-7175 3600)(-7175 3900);
WIRE 16 -1 (-7050 3900)(-7175 3900);
WIRE 16 -1 (-7175 3900)(-8250 3900);
WIRE 16 -1 (-8325 3900)(-8250 3900);
WIRE 16 -1 (-8250 3900)(-8250 3375);
WIRE 16 -1 (-8325 4550)(-8325 3900);
WIRE 16 -1 (-8475 3900)(-8325 3900);
FORCEPROP 2 LAST SIG_NAME H_CPU1_MEMGHJ_MEMHOT_G_N
J 0
(-8460 3910);
DISPLAY 0.617021 (-8460 3910);
PAINT ORANGE (-8460 3910);
WIRE 16 2175 (-7600 3475)(-7600 2800);
WIRE 16 2175 (-8625 3475)(-7600 3475);
WIRE 16 2175 (-7600 2800)(-8625 2800);
WIRE 16 2175 (-8625 2800)(-8625 3475);
WIRE 16 -1 (-7050 1600)(-6800 1600);
WIRE 16 -1 (-7050 1400)(-7050 1600);
WIRE 16 -1 (-7750 1600)(-7050 1600);
FORCEPROP 2 LAST SIG_NAME H_CPU1_MEMGHJ_MEMHOT_LVT3_N
J 0
(-7710 1610);
DISPLAY 0.617021 (-7710 1610);
PAINT ORANGE (-7710 1610);
WIRE 16 -1 (-6800 1400)(-7050 1400);
WIRE 16 -1 (-6800 1825)(-7050 1825);
WIRE 16 -1 (-7050 1825)(-7050 2025);
WIRE 16 -1 (-7050 2025)(-6800 2025);
WIRE 16 -1 (-7750 2025)(-7050 2025);
FORCEPROP 2 LAST SIG_NAME H_CPU0_MEMDEF_MEMHOT_LVT3_N
J 0
(-7710 2035);
DISPLAY 0.617021 (-7710 2035);
PAINT ORANGE (-7710 2035);
WIRE 16 -1 (-7050 1175)(-6800 1175);
WIRE 16 -1 (-7050 975)(-7050 1175);
WIRE 16 -1 (-7775 1175)(-7050 1175);
FORCEPROP 2 LAST SIG_NAME H_CPU1_MEMKLM_MEMHOT_LVT3_N
J 0
(-7735 1185);
DISPLAY 0.617021 (-7735 1185);
PAINT ORANGE (-7735 1185);
WIRE 16 -1 (-6800 975)(-7050 975);
DOT 1 (-8300 3025);
DOT 1 (-8425 3750);
DOT 1 (-8350 3750);
DOT 1 (-8325 3900);
DOT 1 (-8250 3900);
DOT 1 (-8375 4825);
DOT 1 (-7050 1175);
DOT 1 (-7050 1600);
DOT 1 (-7050 2025);
DOT 1 (-7850 3025);
DOT 1 (-7975 4050);
DOT 1 (-7900 4050);
DOT 1 (-7450 3750);
DOT 1 (-7175 3900);
DOT 1 (-7175 4050);
DOT 1 (-7025 2475);
DOT 1 (-5900 3650);
DOT 1 (-5900 3700);
DOT 1 (-4250 2200);
DOT 1 (-7875 4225);
DOT 1 (-7800 4225);
DOT 1 (-7925 4825);
DOT 1 (-7450 4225);
DOT 1 (-4775 4825);
DOT 1 (-3925 1200);
DOT 1 (-2150 1800);
DOT 1 (-3925 2300);
DOT 1 (-3625 2200);
DOT 1 (-3175 3900);
DOT 1 (-3150 4075);
DOT 1 (-2875 3725);
DOT 1 (-1775 1375);
DOT 1 (-1775 1800);
DOT 1 (-2850 4250);
FORCENOTE
ROOM=PROC_SIDEBAND
(-9000 575) 0;
DISPLAY LEFT (-9000 575);
DISPLAY 1.021277 (-9000 575);
PAINT PURPLE (-9000 575);
FORCENOTE
R1U53
(-4200 1900) 0;
DISPLAY LEFT (-4200 1900);
DISPLAY 1.021277 (-4200 1900);
PAINT PURPLE (-4200 1900);
FORCENOTE
R9G34
(-4200 2050) 0;
DISPLAY LEFT (-4200 2050);
DISPLAY 1.021277 (-4200 2050);
PAINT PURPLE (-4200 2050);
FORCENOTE
IE ONLY (NO BMC)
(-4225 2325) 0;
DISPLAY LEFT (-4225 2325);
DISPLAY 1.021277 (-4225 2325);
PAINT PURPLE (-4225 2325);
FORCENOTE
R1U60
(-4200 1825) 0;
DISPLAY LEFT (-4200 1825);
DISPLAY 1.021277 (-4200 1825);
PAINT PURPLE (-4200 1825);
FORCENOTE
R1U59
(-4200 1750) 0;
DISPLAY LEFT (-4200 1750);
DISPLAY 1.021277 (-4200 1750);
PAINT PURPLE (-4200 1750);
FORCENOTE
R9G33
(-4200 1675) 0;
DISPLAY LEFT (-4200 1675);
DISPLAY 1.021277 (-4200 1675);
PAINT PURPLE (-4200 1675);
FORCENOTE
R9G32
(-4200 1600) 0;
DISPLAY LEFT (-4200 1600);
DISPLAY 1.021277 (-4200 1600);
PAINT PURPLE (-4200 1600);
FORCENOTE
R9G28
(-4200 1525) 0;
DISPLAY LEFT (-4200 1525);
DISPLAY 1.021277 (-4200 1525);
PAINT PURPLE (-4200 1525);
FORCENOTE
R2U47
(-4200 1450) 0;
DISPLAY LEFT (-4200 1450);
DISPLAY 1.021277 (-4200 1450);
PAINT PURPLE (-4200 1450);
FORCENOTE
R9G29
(-4200 1375) 0;
DISPLAY LEFT (-4200 1375);
DISPLAY 1.021277 (-4200 1375);
PAINT PURPLE (-4200 1375);
FORCENOTE
R1U54
(-4200 1300) 0;
DISPLAY LEFT (-4200 1300);
DISPLAY 1.021277 (-4200 1300);
PAINT PURPLE (-4200 1300);
FORCENOTE
R2U46
(-4200 1225) 0;
DISPLAY LEFT (-4200 1225);
DISPLAY 1.021277 (-4200 1225);
PAINT PURPLE (-4200 1225);
FORCENOTE
R1U58
(-4200 1975) 0;
DISPLAY LEFT (-4200 1975);
DISPLAY 1.021277 (-4200 1975);
PAINT PURPLE (-4200 1975);
FORCENOTE
U9G1
(-4200 2125) 0;
DISPLAY LEFT (-4200 2125);
DISPLAY 1.021277 (-4200 2125);
PAINT PURPLE (-4200 2125);
FORCENOTE
UNSTUFF
(-4225 2225) 0;
DISPLAY LEFT (-4225 2225);
DISPLAY 1.021277 (-4225 2225);
PAINT PURPLE (-4225 2225);
FORCENOTE
R7D35
(-3875 1375) 0;
DISPLAY LEFT (-3875 1375);
DISPLAY 1.021277 (-3875 1375);
PAINT PURPLE (-3875 1375);
FORCENOTE
R2U45
(-3875 1300) 0;
DISPLAY LEFT (-3875 1300);
DISPLAY 1.021277 (-3875 1300);
PAINT PURPLE (-3875 1300);
FORCENOTE
R9G30
(-3875 1450) 0;
DISPLAY LEFT (-3875 1450);
DISPLAY 1.021277 (-3875 1450);
PAINT PURPLE (-3875 1450);
FORCENOTE
R3N30
(-3875 1525) 0;
DISPLAY LEFT (-3875 1525);
DISPLAY 1.021277 (-3875 1525);
PAINT PURPLE (-3875 1525);
FORCENOTE
R1U56
(-3875 1975) 0;
DISPLAY LEFT (-3875 1975);
DISPLAY 1.021277 (-3875 1975);
PAINT PURPLE (-3875 1975);
FORCENOTE
R1U55
(-3875 1900) 0;
DISPLAY LEFT (-3875 1900);
DISPLAY 1.021277 (-3875 1900);
PAINT PURPLE (-3875 1900);
FORCENOTE
R9G27
(-3875 1825) 0;
DISPLAY LEFT (-3875 1825);
DISPLAY 1.021277 (-3875 1825);
PAINT PURPLE (-3875 1825);
FORCENOTE
R1U57
(-3875 1750) 0;
DISPLAY LEFT (-3875 1750);
DISPLAY 1.021277 (-3875 1750);
PAINT PURPLE (-3875 1750);
FORCENOTE
R1U61
(-3875 1600) 0;
DISPLAY LEFT (-3875 1600);
DISPLAY 1.021277 (-3875 1600);
PAINT PURPLE (-3875 1600);
FORCENOTE
R2U49
(-3875 1675) 0;
DISPLAY LEFT (-3875 1675);
DISPLAY 1.021277 (-3875 1675);
PAINT PURPLE (-3875 1675);
FORCENOTE
R2U51
(-3875 2125) 0;
DISPLAY LEFT (-3875 2125);
DISPLAY 1.021277 (-3875 2125);
PAINT PURPLE (-3875 2125);
FORCENOTE
R1U62
(-3875 2050) 0;
DISPLAY LEFT (-3875 2050);
DISPLAY 1.021277 (-3875 2050);
PAINT PURPLE (-3875 2050);
FORCENOTE
STUFF
(-3875 2225) 0;
DISPLAY LEFT (-3875 2225);
DISPLAY 1.021277 (-3875 2225);
PAINT PURPLE (-3875 2225);
QUIT
